(kicad_sch (version 20230121) (generator eeschema)

  (paper "A3")

  (title_block
    (title "Data Center RDIMM DDR4 Tester")
    (date "2024-09-30")
    (rev "1.2.4")
    (comment 1 "www.antmicro.com")
    (comment 2 "Antmicro Ltd")
  )

  (junction (at 46.99 172.72) (diameter 0) (color 0 0 0 0)
  )
  (junction (at 203.835 217.805) (diameter 0) (color 0 0 0 0)
  )
  (junction (at 194.945 248.285) (diameter 0) (color 0 0 0 0)
  )
  (junction (at 231.14 244.475) (diameter 0) (color 0 0 0 0)
  )
  (junction (at 200.66 226.695) (diameter 0) (color 0 0 0 0)
  )
  (junction (at 139.7 189.865) (diameter 0) (color 0 0 0 0)
  )
  (junction (at 203.835 229.235) (diameter 0) (color 0 0 0 0)
  )

  (no_connect (at 187.325 66.675))
  (no_connect (at 64.135 114.3))
  (no_connect (at 187.325 73.025))
  (no_connect (at 240.665 83.82))
  (no_connect (at 64.135 118.11))
  (no_connect (at 156.21 210.185))
  (no_connect (at 187.325 111.125))
  (no_connect (at 94.615 248.92))
  (no_connect (at 156.845 100.965))
  (no_connect (at 186.69 194.945))
  (no_connect (at 94.615 124.46))
  (no_connect (at 240.665 92.71))
  (no_connect (at 94.615 118.11))
  (no_connect (at 240.665 45.72))
  (no_connect (at 64.135 120.65))
  (no_connect (at 64.135 240.03))
  (no_connect (at 156.845 56.515))
  (no_connect (at 64.135 176.53))
  (no_connect (at 156.845 120.015))
  (no_connect (at 94.615 201.93))
  (no_connect (at 156.845 62.865))
  (no_connect (at 156.21 207.645))
  (no_connect (at 186.69 207.645))
  (no_connect (at 187.325 88.265))
  (no_connect (at 156.845 111.125))
  (no_connect (at 94.615 252.73))
  (no_connect (at 187.325 123.825))
  (no_connect (at 156.21 220.345))
  (no_connect (at 186.69 201.295))
  (no_connect (at 187.325 62.865))
  (no_connect (at 156.845 81.915))
  (no_connect (at 156.21 216.535))
  (no_connect (at 187.325 50.165))
  (no_connect (at 186.69 220.345))
  (no_connect (at 240.665 86.36))
  (no_connect (at 187.325 47.625))
  (no_connect (at 186.69 222.885))
  (no_connect (at 187.325 56.515))
  (no_connect (at 94.615 127))
  (no_connect (at 94.615 120.65))
  (no_connect (at 187.325 113.665))
  (no_connect (at 187.325 120.015))
  (no_connect (at 64.135 111.76))
  (no_connect (at 156.21 213.995))
  (no_connect (at 64.135 242.57))
  (no_connect (at 94.615 57.15))
  (no_connect (at 156.21 184.785))
  (no_connect (at 94.615 204.47))
  (no_connect (at 64.135 248.92))
  (no_connect (at 156.845 107.315))
  (no_connect (at 156.845 60.325))
  (no_connect (at 156.845 69.215))
  (no_connect (at 156.21 194.945))
  (no_connect (at 94.615 73.66))
  (no_connect (at 240.665 48.26))
  (no_connect (at 240.665 54.61))
  (no_connect (at 64.135 246.38))
  (no_connect (at 187.325 94.615))
  (no_connect (at 94.615 246.38))
  (no_connect (at 187.325 117.475))
  (no_connect (at 186.69 203.835))
  (no_connect (at 156.845 53.975))
  (no_connect (at 156.845 117.475))
  (no_connect (at 240.665 118.11))
  (no_connect (at 94.615 76.2))
  (no_connect (at 156.845 79.375))
  (no_connect (at 156.845 88.265))
  (no_connect (at 186.69 191.135))
  (no_connect (at 156.21 203.835))
  (no_connect (at 156.21 188.595))
  (no_connect (at 187.325 98.425))
  (no_connect (at 156.21 201.295))
  (no_connect (at 156.845 85.725))
  (no_connect (at 64.135 198.12))
  (no_connect (at 186.69 188.595))
  (no_connect (at 187.325 69.215))
  (no_connect (at 94.615 176.53))
  (no_connect (at 187.325 79.375))
  (no_connect (at 187.325 60.325))
  (no_connect (at 156.845 73.025))
  (no_connect (at 187.325 85.725))
  (no_connect (at 240.665 52.07))
  (no_connect (at 186.69 210.185))
  (no_connect (at 64.135 179.07))
  (no_connect (at 156.21 235.585))
  (no_connect (at 187.325 107.315))
  (no_connect (at 94.615 179.07))
  (no_connect (at 94.615 111.76))
  (no_connect (at 94.615 107.95))
  (no_connect (at 156.21 244.475))
  (no_connect (at 187.325 126.365))
  (no_connect (at 156.845 113.665))
  (no_connect (at 187.325 81.915))
  (no_connect (at 156.845 104.775))
  (no_connect (at 64.135 233.68))
  (no_connect (at 156.21 191.135))
  (no_connect (at 156.21 222.885))
  (no_connect (at 94.615 54.61))
  (no_connect (at 156.845 98.425))
  (no_connect (at 186.69 244.475))
  (no_connect (at 64.135 107.95))
  (no_connect (at 94.615 114.3))
  (no_connect (at 64.135 105.41))
  (no_connect (at 187.325 75.565))
  (no_connect (at 187.325 92.075))
  (no_connect (at 64.135 67.31))
  (no_connect (at 94.615 105.41))
  (no_connect (at 64.135 195.58))
  (no_connect (at 156.845 75.565))
  (no_connect (at 94.615 255.27))
  (no_connect (at 240.665 90.17))
  (no_connect (at 156.845 66.675))
  (no_connect (at 187.325 104.775))
  (no_connect (at 156.21 197.485))
  (no_connect (at 186.69 197.485))
  (no_connect (at 156.845 94.615))
  (no_connect (at 64.135 236.22))
  (no_connect (at 64.135 69.85))
  (no_connect (at 156.845 50.165))
  (no_connect (at 94.615 242.57))
  (no_connect (at 156.845 92.075))
  (no_connect (at 156.845 47.625))
  (no_connect (at 187.325 100.965))
  (no_connect (at 187.325 53.975))
  (no_connect (at 64.135 101.6))

  (wire (pts (xy 342.9 93.345) (xy 360.68 93.345))
    (stroke (width 0) (type default))
  )
  (wire (pts (xy 59.563 217.17) (xy 64.135 217.17))
    (stroke (width 0) (type default))
  )
  (wire (pts (xy 152.4 239.395) (xy 156.21 239.395))
    (stroke (width 0) (type default))
  )
  (wire (pts (xy 234.315 67.31) (xy 240.665 67.31))
    (stroke (width 0) (type default))
  )
  (wire (pts (xy 342.9 164.465) (xy 360.68 164.465))
    (stroke (width 0) (type default))
  )
  (wire (pts (xy 238.76 123.825) (xy 238.76 121.92))
    (stroke (width 0) (type default))
  )
  (wire (pts (xy 287.02 96.52) (xy 271.145 96.52))
    (stroke (width 0) (type default))
  )
  (wire (pts (xy 94.615 101.6) (xy 97.79 101.6))
    (stroke (width 0) (type default))
  )
  (wire (pts (xy 318.135 66.675) (xy 344.17 66.675))
    (stroke (width 0) (type default))
  )
  (wire (pts (xy 97.79 95.25) (xy 94.615 95.25))
    (stroke (width 0) (type default))
  )
  (wire (pts (xy 60.96 63.5) (xy 64.135 63.5))
    (stroke (width 0) (type default))
  )
  (wire (pts (xy 349.25 44.45) (xy 357.505 44.45))
    (stroke (width 0) (type default))
  )
  (wire (pts (xy 149.86 182.245) (xy 156.21 182.245))
    (stroke (width 0) (type default))
  )
  (wire (pts (xy 154.94 252.095) (xy 156.21 252.095))
    (stroke (width 0) (type default))
  )
  (wire (pts (xy 152.4 231.775) (xy 156.21 231.775))
    (stroke (width 0) (type default))
  )
  (wire (pts (xy 342.9 144.145) (xy 360.68 144.145))
    (stroke (width 0) (type default))
  )
  (wire (pts (xy 186.69 226.695) (xy 200.66 226.695))
    (stroke (width 0) (type default))
  )
  (wire (pts (xy 191.77 252.095) (xy 186.69 252.095))
    (stroke (width 0) (type default))
  )
  (wire (pts (xy 61.595 41.91) (xy 64.135 41.91))
    (stroke (width 0) (type default))
  )
  (wire (pts (xy 319.405 144.145) (xy 337.82 144.145))
    (stroke (width 0) (type default))
  )
  (wire (pts (xy 349.25 64.135) (xy 357.505 64.135))
    (stroke (width 0) (type default))
  )
  (wire (pts (xy 139.7 189.865) (xy 139.7 188.595))
    (stroke (width 0) (type default))
  )
  (wire (pts (xy 135.255 178.435) (xy 156.21 178.435))
    (stroke (width 0) (type default))
  )
  (wire (pts (xy 227.33 244.475) (xy 231.14 244.475))
    (stroke (width 0) (type default))
  )
  (wire (pts (xy 60.325 182.88) (xy 64.135 182.88))
    (stroke (width 0) (type default))
  )
  (wire (pts (xy 205.105 248.285) (xy 194.945 248.285))
    (stroke (width 0) (type default))
  )
  (wire (pts (xy 60.325 191.77) (xy 64.135 191.77))
    (stroke (width 0) (type default))
  )
  (wire (pts (xy 203.835 224.79) (xy 203.835 229.235))
    (stroke (width 0) (type default))
  )
  (wire (pts (xy 94.615 185.42) (xy 98.425 185.42))
    (stroke (width 0) (type default))
  )
  (wire (pts (xy 186.69 178.435) (xy 203.835 178.435))
    (stroke (width 0) (type default))
  )
  (wire (pts (xy 60.96 57.15) (xy 64.135 57.15))
    (stroke (width 0) (type default))
  )
  (wire (pts (xy 354.33 95.885) (xy 360.68 95.885))
    (stroke (width 0) (type default))
  )
  (wire (pts (xy 221.615 99.06) (xy 240.665 99.06))
    (stroke (width 0) (type default))
  )
  (wire (pts (xy 60.96 54.61) (xy 64.135 54.61))
    (stroke (width 0) (type default))
  )
  (wire (pts (xy 349.25 74.295) (xy 357.505 74.295))
    (stroke (width 0) (type default))
  )
  (wire (pts (xy 94.615 80.01) (xy 97.79 80.01))
    (stroke (width 0) (type default))
  )
  (wire (pts (xy 318.135 76.835) (xy 344.17 76.835))
    (stroke (width 0) (type default))
  )
  (wire (pts (xy 186.69 248.285) (xy 194.945 248.285))
    (stroke (width 0) (type default))
  )
  (wire (pts (xy 46.99 172.72) (xy 46.99 168.91))
    (stroke (width 0) (type default))
  )
  (wire (pts (xy 287.02 109.22) (xy 271.145 109.22))
    (stroke (width 0) (type default))
  )
  (wire (pts (xy 139.7 183.515) (xy 139.7 182.245))
    (stroke (width 0) (type default))
  )
  (wire (pts (xy 342.9 123.825) (xy 360.68 123.825))
    (stroke (width 0) (type default))
  )
  (wire (pts (xy 60.325 88.9) (xy 64.135 88.9))
    (stroke (width 0) (type default))
  )
  (wire (pts (xy 354.33 106.045) (xy 360.68 106.045))
    (stroke (width 0) (type default))
  )
  (wire (pts (xy 274.32 52.07) (xy 271.145 52.07))
    (stroke (width 0) (type default))
  )
  (wire (pts (xy 152.4 241.935) (xy 156.21 241.935))
    (stroke (width 0) (type default))
  )
  (wire (pts (xy 97.79 92.71) (xy 94.615 92.71))
    (stroke (width 0) (type default))
  )
  (wire (pts (xy 59.69 208.28) (xy 64.135 208.28))
    (stroke (width 0) (type default))
  )
  (wire (pts (xy 97.79 220.98) (xy 94.615 220.98))
    (stroke (width 0) (type default))
  )
  (wire (pts (xy 139.7 189.865) (xy 149.86 189.865))
    (stroke (width 0) (type default))
  )
  (wire (pts (xy 274.32 48.26) (xy 271.145 48.26))
    (stroke (width 0) (type default))
  )
  (wire (pts (xy 98.425 60.96) (xy 94.615 60.96))
    (stroke (width 0) (type default))
  )
  (wire (pts (xy 98.425 69.85) (xy 94.615 69.85))
    (stroke (width 0) (type default))
  )
  (wire (pts (xy 274.32 67.31) (xy 271.145 67.31))
    (stroke (width 0) (type default))
  )
  (wire (pts (xy 221.615 71.12) (xy 240.665 71.12))
    (stroke (width 0) (type default))
  )
  (wire (pts (xy 274.32 60.96) (xy 271.145 60.96))
    (stroke (width 0) (type default))
  )
  (wire (pts (xy 60.325 99.06) (xy 64.135 99.06))
    (stroke (width 0) (type default))
  )
  (wire (pts (xy 274.32 64.77) (xy 271.145 64.77))
    (stroke (width 0) (type default))
  )
  (wire (pts (xy 203.835 217.805) (xy 200.66 217.805))
    (stroke (width 0) (type default))
  )
  (wire (pts (xy 152.4 229.235) (xy 156.21 229.235))
    (stroke (width 0) (type default))
  )
  (wire (pts (xy 62.23 124.46) (xy 62.23 126.365))
    (stroke (width 0) (type default))
  )
  (wire (pts (xy 97.79 195.58) (xy 94.615 195.58))
    (stroke (width 0) (type default))
  )
  (wire (pts (xy 60.96 73.66) (xy 64.135 73.66))
    (stroke (width 0) (type default))
  )
  (wire (pts (xy 45.72 48.26) (xy 64.135 48.26))
    (stroke (width 0) (type default))
  )
  (wire (pts (xy 349.25 76.835) (xy 357.505 76.835))
    (stroke (width 0) (type default))
  )
  (wire (pts (xy 319.405 123.825) (xy 337.82 123.825))
    (stroke (width 0) (type default))
  )
  (wire (pts (xy 287.02 90.17) (xy 271.145 90.17))
    (stroke (width 0) (type default))
  )
  (wire (pts (xy 342.9 103.505) (xy 360.68 103.505))
    (stroke (width 0) (type default))
  )
  (wire (pts (xy 137.795 189.865) (xy 139.7 189.865))
    (stroke (width 0) (type default))
  )
  (wire (pts (xy 234.315 60.96) (xy 240.665 60.96))
    (stroke (width 0) (type default))
  )
  (wire (pts (xy 186.69 184.785) (xy 191.77 184.785))
    (stroke (width 0) (type default))
  )
  (wire (pts (xy 221.615 105.41) (xy 240.665 105.41))
    (stroke (width 0) (type default))
  )
  (wire (pts (xy 60.325 86.36) (xy 64.135 86.36))
    (stroke (width 0) (type default))
  )
  (wire (pts (xy 274.32 73.66) (xy 271.145 73.66))
    (stroke (width 0) (type default))
  )
  (wire (pts (xy 318.135 64.135) (xy 344.17 64.135))
    (stroke (width 0) (type default))
  )
  (wire (pts (xy 60.325 92.71) (xy 64.135 92.71))
    (stroke (width 0) (type default))
  )
  (wire (pts (xy 287.02 105.41) (xy 271.145 105.41))
    (stroke (width 0) (type default))
  )
  (wire (pts (xy 238.76 244.475) (xy 238.76 246.38))
    (stroke (width 0) (type default))
  )
  (wire (pts (xy 287.02 99.06) (xy 271.145 99.06))
    (stroke (width 0) (type default))
  )
  (wire (pts (xy 97.79 233.68) (xy 94.615 233.68))
    (stroke (width 0) (type default))
  )
  (wire (pts (xy 97.79 227.33) (xy 94.615 227.33))
    (stroke (width 0) (type default))
  )
  (wire (pts (xy 154.305 41.275) (xy 156.845 41.275))
    (stroke (width 0) (type default))
  )
  (wire (pts (xy 354.33 156.845) (xy 360.68 156.845))
    (stroke (width 0) (type default))
  )
  (wire (pts (xy 238.76 121.92) (xy 240.665 121.92))
    (stroke (width 0) (type default))
  )
  (wire (pts (xy 97.79 88.9) (xy 94.615 88.9))
    (stroke (width 0) (type default))
  )
  (wire (pts (xy 97.79 236.22) (xy 94.615 236.22))
    (stroke (width 0) (type default))
  )
  (wire (pts (xy 318.135 53.975) (xy 344.17 53.975))
    (stroke (width 0) (type default))
  )
  (wire (pts (xy 59.69 229.87) (xy 64.135 229.87))
    (stroke (width 0) (type default))
  )
  (wire (pts (xy 139.7 182.245) (xy 137.795 182.245))
    (stroke (width 0) (type default))
  )
  (wire (pts (xy 349.25 46.99) (xy 357.505 46.99))
    (stroke (width 0) (type default))
  )
  (wire (pts (xy 203.835 229.235) (xy 207.645 229.235))
    (stroke (width 0) (type default))
  )
  (wire (pts (xy 97.79 223.52) (xy 94.615 223.52))
    (stroke (width 0) (type default))
  )
  (wire (pts (xy 221.615 96.52) (xy 240.665 96.52))
    (stroke (width 0) (type default))
  )
  (wire (pts (xy 97.79 210.82) (xy 94.615 210.82))
    (stroke (width 0) (type default))
  )
  (wire (pts (xy 287.02 86.36) (xy 271.145 86.36))
    (stroke (width 0) (type default))
  )
  (wire (pts (xy 287.02 92.71) (xy 271.145 92.71))
    (stroke (width 0) (type default))
  )
  (wire (pts (xy 154.94 123.825) (xy 154.94 125.73))
    (stroke (width 0) (type default))
  )
  (wire (pts (xy 205.105 245.11) (xy 203.835 245.11))
    (stroke (width 0) (type default))
  )
  (wire (pts (xy 186.69 175.895) (xy 203.835 175.895))
    (stroke (width 0) (type default))
  )
  (wire (pts (xy 145.415 169.545) (xy 148.59 169.545))
    (stroke (width 0) (type default))
  )
  (wire (pts (xy 319.405 116.205) (xy 349.25 116.205))
    (stroke (width 0) (type default))
  )
  (wire (pts (xy 62.23 254.635) (xy 62.23 252.73))
    (stroke (width 0) (type default))
  )
  (wire (pts (xy 97.79 240.03) (xy 94.615 240.03))
    (stroke (width 0) (type default))
  )
  (wire (pts (xy 94.615 82.55) (xy 97.79 82.55))
    (stroke (width 0) (type default))
  )
  (wire (pts (xy 319.405 133.985) (xy 337.82 133.985))
    (stroke (width 0) (type default))
  )
  (wire (pts (xy 319.405 164.465) (xy 337.82 164.465))
    (stroke (width 0) (type default))
  )
  (wire (pts (xy 319.405 154.305) (xy 337.82 154.305))
    (stroke (width 0) (type default))
  )
  (wire (pts (xy 97.79 198.12) (xy 94.615 198.12))
    (stroke (width 0) (type default))
  )
  (wire (pts (xy 45.72 50.8) (xy 64.135 50.8))
    (stroke (width 0) (type default))
  )
  (wire (pts (xy 319.405 167.005) (xy 349.25 167.005))
    (stroke (width 0) (type default))
  )
  (wire (pts (xy 94.615 99.06) (xy 97.79 99.06))
    (stroke (width 0) (type default))
  )
  (wire (pts (xy 97.79 191.77) (xy 94.615 191.77))
    (stroke (width 0) (type default))
  )
  (wire (pts (xy 113.665 48.26) (xy 94.615 48.26))
    (stroke (width 0) (type default))
  )
  (wire (pts (xy 354.33 116.205) (xy 360.68 116.205))
    (stroke (width 0) (type default))
  )
  (wire (pts (xy 43.815 172.72) (xy 46.99 172.72))
    (stroke (width 0) (type default))
  )
  (wire (pts (xy 354.33 146.685) (xy 360.68 146.685))
    (stroke (width 0) (type default))
  )
  (wire (pts (xy 231.14 244.475) (xy 238.76 244.475))
    (stroke (width 0) (type default))
  )
  (wire (pts (xy 60.325 80.01) (xy 64.135 80.01))
    (stroke (width 0) (type default))
  )
  (wire (pts (xy 318.135 74.295) (xy 344.17 74.295))
    (stroke (width 0) (type default))
  )
  (wire (pts (xy 287.02 102.87) (xy 271.145 102.87))
    (stroke (width 0) (type default))
  )
  (wire (pts (xy 234.315 39.37) (xy 240.665 39.37))
    (stroke (width 0) (type default))
  )
  (wire (pts (xy 234.315 64.77) (xy 240.665 64.77))
    (stroke (width 0) (type default))
  )
  (wire (pts (xy 196.215 245.11) (xy 194.945 245.11))
    (stroke (width 0) (type default))
  )
  (wire (pts (xy 287.02 111.76) (xy 271.145 111.76))
    (stroke (width 0) (type default))
  )
  (wire (pts (xy 203.835 219.71) (xy 203.835 217.805))
    (stroke (width 0) (type default))
  )
  (wire (pts (xy 149.86 189.865) (xy 149.86 182.245))
    (stroke (width 0) (type default))
  )
  (wire (pts (xy 59.69 223.52) (xy 64.135 223.52))
    (stroke (width 0) (type default))
  )
  (wire (pts (xy 97.79 229.87) (xy 94.615 229.87))
    (stroke (width 0) (type default))
  )
  (wire (pts (xy 154.94 253.365) (xy 154.94 252.095))
    (stroke (width 0) (type default))
  )
  (wire (pts (xy 97.79 217.17) (xy 94.615 217.17))
    (stroke (width 0) (type default))
  )
  (wire (pts (xy 274.32 58.42) (xy 271.145 58.42))
    (stroke (width 0) (type default))
  )
  (wire (pts (xy 354.33 167.005) (xy 360.68 167.005))
    (stroke (width 0) (type default))
  )
  (wire (pts (xy 354.33 136.525) (xy 360.68 136.525))
    (stroke (width 0) (type default))
  )
  (wire (pts (xy 319.405 146.685) (xy 349.25 146.685))
    (stroke (width 0) (type default))
  )
  (wire (pts (xy 200.66 226.695) (xy 207.645 226.695))
    (stroke (width 0) (type default))
  )
  (wire (pts (xy 154.94 123.825) (xy 156.845 123.825))
    (stroke (width 0) (type default))
  )
  (wire (pts (xy 60.325 82.55) (xy 64.135 82.55))
    (stroke (width 0) (type default))
  )
  (wire (pts (xy 319.405 136.525) (xy 349.25 136.525))
    (stroke (width 0) (type default))
  )
  (wire (pts (xy 60.325 95.25) (xy 64.135 95.25))
    (stroke (width 0) (type default))
  )
  (wire (pts (xy 318.135 44.45) (xy 344.17 44.45))
    (stroke (width 0) (type default))
  )
  (wire (pts (xy 349.25 66.675) (xy 357.505 66.675))
    (stroke (width 0) (type default))
  )
  (wire (pts (xy 59.69 204.47) (xy 64.135 204.47))
    (stroke (width 0) (type default))
  )
  (wire (pts (xy 152.4 226.695) (xy 156.21 226.695))
    (stroke (width 0) (type default))
  )
  (wire (pts (xy 59.69 210.82) (xy 64.135 210.82))
    (stroke (width 0) (type default))
  )
  (wire (pts (xy 60.96 76.2) (xy 64.135 76.2))
    (stroke (width 0) (type default))
  )
  (wire (pts (xy 319.405 106.045) (xy 349.25 106.045))
    (stroke (width 0) (type default))
  )
  (wire (pts (xy 207.645 217.805) (xy 203.835 217.805))
    (stroke (width 0) (type default))
  )
  (wire (pts (xy 62.865 170.18) (xy 64.135 170.18))
    (stroke (width 0) (type default))
  )
  (wire (pts (xy 97.79 86.36) (xy 94.615 86.36))
    (stroke (width 0) (type default))
  )
  (wire (pts (xy 342.9 133.985) (xy 360.68 133.985))
    (stroke (width 0) (type default))
  )
  (wire (pts (xy 98.425 67.31) (xy 94.615 67.31))
    (stroke (width 0) (type default))
  )
  (wire (pts (xy 62.23 124.46) (xy 64.135 124.46))
    (stroke (width 0) (type default))
  )
  (wire (pts (xy 274.32 54.61) (xy 271.145 54.61))
    (stroke (width 0) (type default))
  )
  (wire (pts (xy 46.99 172.72) (xy 64.135 172.72))
    (stroke (width 0) (type default))
  )
  (wire (pts (xy 186.69 229.235) (xy 203.835 229.235))
    (stroke (width 0) (type default))
  )
  (wire (pts (xy 60.325 189.23) (xy 64.135 189.23))
    (stroke (width 0) (type default))
  )
  (wire (pts (xy 319.405 95.885) (xy 349.25 95.885))
    (stroke (width 0) (type default))
  )
  (wire (pts (xy 319.405 103.505) (xy 337.82 103.505))
    (stroke (width 0) (type default))
  )
  (wire (pts (xy 59.69 201.93) (xy 64.135 201.93))
    (stroke (width 0) (type default))
  )
  (wire (pts (xy 200.66 224.79) (xy 200.66 226.695))
    (stroke (width 0) (type default))
  )
  (wire (pts (xy 153.67 169.545) (xy 156.21 169.545))
    (stroke (width 0) (type default))
  )
  (wire (pts (xy 342.9 154.305) (xy 360.68 154.305))
    (stroke (width 0) (type default))
  )
  (wire (pts (xy 349.25 53.975) (xy 357.505 53.975))
    (stroke (width 0) (type default))
  )
  (wire (pts (xy 349.25 56.515) (xy 357.505 56.515))
    (stroke (width 0) (type default))
  )
  (wire (pts (xy 274.32 45.72) (xy 271.145 45.72))
    (stroke (width 0) (type default))
  )
  (wire (pts (xy 59.69 220.98) (xy 64.135 220.98))
    (stroke (width 0) (type default))
  )
  (wire (pts (xy 97.79 214.63) (xy 94.615 214.63))
    (stroke (width 0) (type default))
  )
  (wire (pts (xy 186.69 182.245) (xy 191.77 182.245))
    (stroke (width 0) (type default))
  )
  (wire (pts (xy 98.425 63.5) (xy 94.615 63.5))
    (stroke (width 0) (type default))
  )
  (wire (pts (xy 62.23 252.73) (xy 64.135 252.73))
    (stroke (width 0) (type default))
  )
  (wire (pts (xy 354.33 126.365) (xy 360.68 126.365))
    (stroke (width 0) (type default))
  )
  (wire (pts (xy 319.405 156.845) (xy 349.25 156.845))
    (stroke (width 0) (type default))
  )
  (wire (pts (xy 194.945 248.285) (xy 194.945 245.11))
    (stroke (width 0) (type default))
  )
  (wire (pts (xy 46.99 161.925) (xy 43.815 161.925))
    (stroke (width 0) (type default))
  )
  (wire (pts (xy 200.66 217.805) (xy 200.66 219.71))
    (stroke (width 0) (type default))
  )
  (wire (pts (xy 59.563 214.63) (xy 64.135 214.63))
    (stroke (width 0) (type default))
  )
  (wire (pts (xy 319.405 126.365) (xy 349.25 126.365))
    (stroke (width 0) (type default))
  )
  (wire (pts (xy 135.255 175.895) (xy 156.21 175.895))
    (stroke (width 0) (type default))
  )
  (wire (pts (xy 221.615 73.66) (xy 240.665 73.66))
    (stroke (width 0) (type default))
  )
  (wire (pts (xy 319.405 93.345) (xy 337.82 93.345))
    (stroke (width 0) (type default))
  )
  (wire (pts (xy 274.32 71.12) (xy 271.145 71.12))
    (stroke (width 0) (type default))
  )
  (wire (pts (xy 97.79 208.28) (xy 94.615 208.28))
    (stroke (width 0) (type default))
  )
  (wire (pts (xy 287.02 83.82) (xy 271.145 83.82))
    (stroke (width 0) (type default))
  )
  (wire (pts (xy 221.615 102.87) (xy 240.665 102.87))
    (stroke (width 0) (type default))
  )
  (wire (pts (xy 94.615 182.88) (xy 98.425 182.88))
    (stroke (width 0) (type default))
  )
  (wire (pts (xy 60.96 60.96) (xy 64.135 60.96))
    (stroke (width 0) (type default))
  )
  (wire (pts (xy 234.315 58.42) (xy 240.665 58.42))
    (stroke (width 0) (type default))
  )
  (wire (pts (xy 319.405 113.665) (xy 337.82 113.665))
    (stroke (width 0) (type default))
  )
  (wire (pts (xy 60.325 185.42) (xy 64.135 185.42))
    (stroke (width 0) (type default))
  )
  (wire (pts (xy 318.135 46.99) (xy 344.17 46.99))
    (stroke (width 0) (type default))
  )
  (wire (pts (xy 318.135 56.515) (xy 344.17 56.515))
    (stroke (width 0) (type default))
  )
  (wire (pts (xy 46.99 163.83) (xy 46.99 161.925))
    (stroke (width 0) (type default))
  )
  (wire (pts (xy 113.665 50.8) (xy 94.615 50.8))
    (stroke (width 0) (type default))
  )
  (wire (pts (xy 231.14 244.475) (xy 231.14 246.38))
    (stroke (width 0) (type default))
  )
  (wire (pts (xy 342.9 113.665) (xy 360.68 113.665))
    (stroke (width 0) (type default))
  )
  (wire (pts (xy 97.79 189.23) (xy 94.615 189.23))
    (stroke (width 0) (type default))
  )
  (wire (pts (xy 59.69 227.33) (xy 64.135 227.33))
    (stroke (width 0) (type default))
  )

  (text "FMC HPC" (at 17.78 20.32 0)
    (effects (font (size 2.4892 2.4892) (thickness 0.4978) bold) (justify left bottom))
  )
  (text "Place close to connector" (at 332.74 87.757 0)
    (effects (font (size 1.27 1.27)) (justify left bottom))
  )
  (text "Resistors needed to comply with standard HCSL PCIe clock.\nRoute REFCLK as 50 Ohm SE (or 100 Ohm diff)"
    (at 317.5 37.465 0)
    (effects (font (size 1.27 1.27)) (justify left bottom))
  )

  (label "GTX_TX2_C_N" (at 287.02 92.71 180) (fields_autoplaced)
    (effects (font (size 1.27 1.27)) (justify right bottom))
  )
  (label "GTX_TX3_C_N" (at 319.405 126.365 0) (fields_autoplaced)
    (effects (font (size 1.27 1.27)) (justify left bottom))
  )
  (label "GTX_TX4_C_P" (at 319.405 133.985 0) (fields_autoplaced)
    (effects (font (size 1.27 1.27)) (justify left bottom))
  )
  (label "GTX_TX0_C_P" (at 319.405 93.345 0) (fields_autoplaced)
    (effects (font (size 1.27 1.27)) (justify left bottom))
  )
  (label "GTX_TX7_C_P" (at 221.615 96.52 0) (fields_autoplaced)
    (effects (font (size 1.27 1.27)) (justify left bottom))
  )
  (label "GTX_TX5_C_N" (at 287.02 111.76 180) (fields_autoplaced)
    (effects (font (size 1.27 1.27)) (justify right bottom))
  )
  (label "GTR_REFCLK0_R_N" (at 318.135 46.99 0) (fields_autoplaced)
    (effects (font (size 1.27 1.27)) (justify left bottom))
  )
  (label "GTX_TX2_C_N" (at 319.405 116.205 0) (fields_autoplaced)
    (effects (font (size 1.27 1.27)) (justify left bottom))
  )
  (label "GTX_TX5_C_N" (at 319.405 146.685 0) (fields_autoplaced)
    (effects (font (size 1.27 1.27)) (justify left bottom))
  )
  (label "GTX_TX7_C_N" (at 319.405 167.005 0) (fields_autoplaced)
    (effects (font (size 1.27 1.27)) (justify left bottom))
  )
  (label "GTX_TX5_C_P" (at 319.405 144.145 0) (fields_autoplaced)
    (effects (font (size 1.27 1.27)) (justify left bottom))
  )
  (label "GTX_TX6_C_N" (at 221.615 105.41 0) (fields_autoplaced)
    (effects (font (size 1.27 1.27)) (justify left bottom))
  )
  (label "GTR_REFCLK1_R_N" (at 318.135 56.515 0) (fields_autoplaced)
    (effects (font (size 1.27 1.27)) (justify left bottom))
  )
  (label "GTX_TX1_C_P" (at 319.405 103.505 0) (fields_autoplaced)
    (effects (font (size 1.27 1.27)) (justify left bottom))
  )
  (label "GTR_REFCLK3_R_N" (at 318.135 76.835 0) (fields_autoplaced)
    (effects (font (size 1.27 1.27)) (justify left bottom))
  )
  (label "GTR_REFCLK1_R_P" (at 221.615 71.12 0) (fields_autoplaced)
    (effects (font (size 1.27 1.27)) (justify left bottom))
  )
  (label "GTR_REFCLK2_R_N" (at 45.72 50.8 0) (fields_autoplaced)
    (effects (font (size 1.27 1.27)) (justify left bottom))
  )
  (label "GTX_TX1_C_N" (at 287.02 86.36 180) (fields_autoplaced)
    (effects (font (size 1.27 1.27)) (justify right bottom))
  )
  (label "GTX_TX2_C_P" (at 287.02 90.17 180) (fields_autoplaced)
    (effects (font (size 1.27 1.27)) (justify right bottom))
  )
  (label "GTR_REFCLK2_R_N" (at 318.135 66.675 0) (fields_autoplaced)
    (effects (font (size 1.27 1.27)) (justify left bottom))
  )
  (label "GTR_REFCLK3_R_P" (at 318.135 74.295 0) (fields_autoplaced)
    (effects (font (size 1.27 1.27)) (justify left bottom))
  )
  (label "GTR_REFCLK0_R_P" (at 135.255 175.895 0) (fields_autoplaced)
    (effects (font (size 1.27 1.27)) (justify left bottom))
  )
  (label "GTX_TX4_C_N" (at 319.405 136.525 0) (fields_autoplaced)
    (effects (font (size 1.27 1.27)) (justify left bottom))
  )
  (label "GTX_TX5_C_P" (at 287.02 109.22 180) (fields_autoplaced)
    (effects (font (size 1.27 1.27)) (justify right bottom))
  )
  (label "GTX_TX3_C_P" (at 319.405 123.825 0) (fields_autoplaced)
    (effects (font (size 1.27 1.27)) (justify left bottom))
  )
  (label "GTX_TX2_C_P" (at 319.405 113.665 0) (fields_autoplaced)
    (effects (font (size 1.27 1.27)) (justify left bottom))
  )
  (label "GTR_REFCLK0_R_N" (at 135.255 178.435 0) (fields_autoplaced)
    (effects (font (size 1.27 1.27)) (justify left bottom))
  )
  (label "GTX_TX0_C_N" (at 319.405 95.885 0) (fields_autoplaced)
    (effects (font (size 1.27 1.27)) (justify left bottom))
  )
  (label "GTX_TX7_C_N" (at 221.615 99.06 0) (fields_autoplaced)
    (effects (font (size 1.27 1.27)) (justify left bottom))
  )
  (label "GTR_REFCLK0_R_P" (at 318.135 44.45 0) (fields_autoplaced)
    (effects (font (size 1.27 1.27)) (justify left bottom))
  )
  (label "GTX_TX0_C_P" (at 203.835 175.895 180) (fields_autoplaced)
    (effects (font (size 1.27 1.27)) (justify right bottom))
  )
  (label "GTR_REFCLK2_R_P" (at 318.135 64.135 0) (fields_autoplaced)
    (effects (font (size 1.27 1.27)) (justify left bottom))
  )
  (label "GTX_TX6_C_P" (at 319.405 154.305 0) (fields_autoplaced)
    (effects (font (size 1.27 1.27)) (justify left bottom))
  )
  (label "GTX_TX6_C_N" (at 319.405 156.845 0) (fields_autoplaced)
    (effects (font (size 1.27 1.27)) (justify left bottom))
  )
  (label "GTX_TX1_C_N" (at 319.405 106.045 0) (fields_autoplaced)
    (effects (font (size 1.27 1.27)) (justify left bottom))
  )
  (label "GTR_REFCLK1_R_N" (at 221.615 73.66 0) (fields_autoplaced)
    (effects (font (size 1.27 1.27)) (justify left bottom))
  )
  (label "GTR_REFCLK3_R_N" (at 113.665 50.8 180) (fields_autoplaced)
    (effects (font (size 1.27 1.27)) (justify right bottom))
  )
  (label "GTX_TX3_C_P" (at 287.02 96.52 180) (fields_autoplaced)
    (effects (font (size 1.27 1.27)) (justify right bottom))
  )
  (label "GTR_REFCLK1_R_P" (at 318.135 53.975 0) (fields_autoplaced)
    (effects (font (size 1.27 1.27)) (justify left bottom))
  )
  (label "GTX_TX1_C_P" (at 287.02 83.82 180) (fields_autoplaced)
    (effects (font (size 1.27 1.27)) (justify right bottom))
  )
  (label "GTX_TX3_C_N" (at 287.02 99.06 180) (fields_autoplaced)
    (effects (font (size 1.27 1.27)) (justify right bottom))
  )
  (label "GTX_TX0_C_N" (at 203.835 178.435 180) (fields_autoplaced)
    (effects (font (size 1.27 1.27)) (justify right bottom))
  )
  (label "GTX_TX7_C_P" (at 319.405 164.465 0) (fields_autoplaced)
    (effects (font (size 1.27 1.27)) (justify left bottom))
  )
  (label "GTR_REFCLK3_R_P" (at 113.665 48.26 180) (fields_autoplaced)
    (effects (font (size 1.27 1.27)) (justify right bottom))
  )
  (label "GTX_TX6_C_P" (at 221.615 102.87 0) (fields_autoplaced)
    (effects (font (size 1.27 1.27)) (justify left bottom))
  )
  (label "GTX_TX4_C_P" (at 287.02 102.87 180) (fields_autoplaced)
    (effects (font (size 1.27 1.27)) (justify right bottom))
  )
  (label "GTX_TX4_C_N" (at 287.02 105.41 180) (fields_autoplaced)
    (effects (font (size 1.27 1.27)) (justify right bottom))
  )
  (label "GTR_REFCLK2_R_P" (at 45.72 48.26 0) (fields_autoplaced)
    (effects (font (size 1.27 1.27)) (justify left bottom))
  )

  (global_label "FMC_IO_13_P" (shape input) (at 60.325 80.01 180) (fields_autoplaced)
    (effects (font (size 1.27 1.27)) (justify right))
    (property "Intersheetrefs" "${INTERSHEET_REFS}" (at 46.8732 79.9306 0)
      (effects (font (size 1.27 1.27)) (justify right) hide)
    )
  )
  (global_label "GTX_RX2_N" (shape input) (at 274.32 54.61 0) (fields_autoplaced)
    (effects (font (size 1.27 1.27)) (justify left))
    (property "Intersheetrefs" "${INTERSHEET_REFS}" (at 287.0461 54.5306 0)
      (effects (font (size 1.27 1.27)) (justify left) hide)
    )
  )
  (global_label "FMC_IO_13_N" (shape input) (at 60.325 82.55 180) (fields_autoplaced)
    (effects (font (size 1.27 1.27)) (justify right))
    (property "Intersheetrefs" "${INTERSHEET_REFS}" (at 46.8127 82.4706 0)
      (effects (font (size 1.27 1.27)) (justify right) hide)
    )
  )
  (global_label "FMC_IO_11_N" (shape input) (at 60.325 88.9 180) (fields_autoplaced)
    (effects (font (size 1.27 1.27)) (justify right))
    (property "Intersheetrefs" "${INTERSHEET_REFS}" (at 46.8127 88.8206 0)
      (effects (font (size 1.27 1.27)) (justify right) hide)
    )
  )
  (global_label "GTX_TX1_P" (shape input) (at 360.68 103.505 0) (fields_autoplaced)
    (effects (font (size 1.27 1.27)) (justify left))
    (property "Intersheetrefs" "${INTERSHEET_REFS}" (at 373.0432 103.4256 0)
      (effects (font (size 1.27 1.27)) (justify left) hide)
    )
  )
  (global_label "FMC_IO_4_N" (shape input) (at 59.69 204.47 180) (fields_autoplaced)
    (effects (font (size 1.27 1.27)) (justify right))
    (property "Intersheetrefs" "${INTERSHEET_REFS}" (at 46.1777 204.3906 0)
      (effects (font (size 1.27 1.27)) (justify right) hide)
    )
  )
  (global_label "FMC_IO_7_P" (shape input) (at 59.69 227.33 180) (fields_autoplaced)
    (effects (font (size 1.27 1.27)) (justify right))
    (property "Intersheetrefs" "${INTERSHEET_REFS}" (at 46.2382 227.2506 0)
      (effects (font (size 1.27 1.27)) (justify right) hide)
    )
  )
  (global_label "GTX_RX6_P" (shape input) (at 234.315 64.77 180) (fields_autoplaced)
    (effects (font (size 1.27 1.27)) (justify right))
    (property "Intersheetrefs" "${INTERSHEET_REFS}" (at 221.6494 64.6906 0)
      (effects (font (size 1.27 1.27)) (justify right) hide)
    )
  )
  (global_label "FMC_IO_7_N" (shape input) (at 59.69 229.87 180) (fields_autoplaced)
    (effects (font (size 1.27 1.27)) (justify right))
    (property "Intersheetrefs" "${INTERSHEET_REFS}" (at 46.1777 229.7906 0)
      (effects (font (size 1.27 1.27)) (justify right) hide)
    )
  )
  (global_label "GTR_REFCLK0_C_P" (shape input) (at 357.505 44.45 0) (fields_autoplaced)
    (effects (font (size 1.27 1.27)) (justify left))
    (property "Intersheetrefs" "${INTERSHEET_REFS}" (at 377.0649 44.3706 0)
      (effects (font (size 1.27 1.27)) (justify left) hide)
    )
  )
  (global_label "FMC_IO_18_N" (shape input) (at 98.425 63.5 0) (fields_autoplaced)
    (effects (font (size 1.27 1.27)) (justify left))
    (property "Intersheetrefs" "${INTERSHEET_REFS}" (at 111.9373 63.4206 0)
      (effects (font (size 1.27 1.27)) (justify left) hide)
    )
  )
  (global_label "FMC_IO_6_N" (shape input) (at 97.79 223.52 0) (fields_autoplaced)
    (effects (font (size 1.27 1.27)) (justify left))
    (property "Intersheetrefs" "${INTERSHEET_REFS}" (at 111.3023 223.4406 0)
      (effects (font (size 1.27 1.27)) (justify left) hide)
    )
  )
  (global_label "FMC_IO_8_P" (shape input) (at 97.79 227.33 0) (fields_autoplaced)
    (effects (font (size 1.27 1.27)) (justify left))
    (property "Intersheetrefs" "${INTERSHEET_REFS}" (at 111.2418 227.2506 0)
      (effects (font (size 1.27 1.27)) (justify left) hide)
    )
  )
  (global_label "GTR_REFCLK3_C_P" (shape input) (at 357.505 74.295 0) (fields_autoplaced)
    (effects (font (size 1.27 1.27)) (justify left))
    (property "Intersheetrefs" "${INTERSHEET_REFS}" (at 377.0649 74.2156 0)
      (effects (font (size 1.27 1.27)) (justify left) hide)
    )
  )
  (global_label "FMC_IO_2_N" (shape input) (at 97.79 210.82 0) (fields_autoplaced)
    (effects (font (size 1.27 1.27)) (justify left))
    (property "Intersheetrefs" "${INTERSHEET_REFS}" (at 111.3023 210.7406 0)
      (effects (font (size 1.27 1.27)) (justify left) hide)
    )
  )
  (global_label "FMC_IO_0" (shape input) (at 97.79 240.03 0) (fields_autoplaced)
    (effects (font (size 1.27 1.27)) (justify left))
    (property "Intersheetrefs" "${INTERSHEET_REFS}" (at 109.0042 239.9506 0)
      (effects (font (size 1.27 1.27)) (justify left) hide)
    )
  )
  (global_label "FMC_IO_8_N" (shape input) (at 97.79 229.87 0) (fields_autoplaced)
    (effects (font (size 1.27 1.27)) (justify left))
    (property "Intersheetrefs" "${INTERSHEET_REFS}" (at 111.3023 229.7906 0)
      (effects (font (size 1.27 1.27)) (justify left) hide)
    )
  )
  (global_label "EXT_ETH3_N" (shape input) (at 60.325 191.77 180) (fields_autoplaced)
    (effects (font (size 1.27 1.27)) (justify right))
    (property "Intersheetrefs" "${INTERSHEET_REFS}" (at 46.7522 191.6906 0)
      (effects (font (size 1.27 1.27)) (justify right) hide)
    )
  )
  (global_label "EXT_ETH2_N" (shape input) (at 97.79 191.77 0) (fields_autoplaced)
    (effects (font (size 1.27 1.27)) (justify left))
    (property "Intersheetrefs" "${INTERSHEET_REFS}" (at 111.3628 191.6906 0)
      (effects (font (size 1.27 1.27)) (justify left) hide)
    )
  )
  (global_label "FMC_IO_10_P" (shape input) (at 59.69 220.98 180) (fields_autoplaced)
    (effects (font (size 1.27 1.27)) (justify right))
    (property "Intersheetrefs" "${INTERSHEET_REFS}" (at 46.2382 220.9006 0)
      (effects (font (size 1.27 1.27)) (justify right) hide)
    )
  )
  (global_label "GTX_RX2_P" (shape input) (at 274.32 52.07 0) (fields_autoplaced)
    (effects (font (size 1.27 1.27)) (justify left))
    (property "Intersheetrefs" "${INTERSHEET_REFS}" (at 286.9856 51.9906 0)
      (effects (font (size 1.27 1.27)) (justify left) hide)
    )
  )
  (global_label "FMC_IO_5_P" (shape input) (at 97.79 80.01 0) (fields_autoplaced)
    (effects (font (size 1.27 1.27)) (justify left))
    (property "Intersheetrefs" "${INTERSHEET_REFS}" (at 111.2418 79.9306 0)
      (effects (font (size 1.27 1.27)) (justify left) hide)
    )
  )
  (global_label "AUX_JTAG_TCK" (shape input) (at 152.4 226.695 180) (fields_autoplaced)
    (effects (font (size 1.27 1.27)) (justify right))
    (property "Intersheetrefs" "${INTERSHEET_REFS}" (at 300.99 299.085 0)
      (effects (font (size 1.27 1.27)) hide)
    )
  )
  (global_label "GTX_RX3_N" (shape input) (at 274.32 60.96 0) (fields_autoplaced)
    (effects (font (size 1.27 1.27)) (justify left))
    (property "Intersheetrefs" "${INTERSHEET_REFS}" (at 287.0461 60.8806 0)
      (effects (font (size 1.27 1.27)) (justify left) hide)
    )
  )
  (global_label "GTX_TX3_P" (shape input) (at 360.68 123.825 0) (fields_autoplaced)
    (effects (font (size 1.27 1.27)) (justify left))
    (property "Intersheetrefs" "${INTERSHEET_REFS}" (at 373.0432 123.7456 0)
      (effects (font (size 1.27 1.27)) (justify left) hide)
    )
  )
  (global_label "EXT_ETH1_N" (shape input) (at 60.325 185.42 180) (fields_autoplaced)
    (effects (font (size 1.27 1.27)) (justify right))
    (property "Intersheetrefs" "${INTERSHEET_REFS}" (at 46.7522 185.3406 0)
      (effects (font (size 1.27 1.27)) (justify right) hide)
    )
  )
  (global_label "FMC_IO_21_N" (shape input) (at 60.96 63.5 180) (fields_autoplaced)
    (effects (font (size 1.27 1.27)) (justify right))
    (property "Intersheetrefs" "${INTERSHEET_REFS}" (at 47.4477 63.4206 0)
      (effects (font (size 1.27 1.27)) (justify right) hide)
    )
  )
  (global_label "FMC_IO_3_P" (shape input) (at 59.69 208.28 180) (fields_autoplaced)
    (effects (font (size 1.27 1.27)) (justify right))
    (property "Intersheetrefs" "${INTERSHEET_REFS}" (at 46.2382 208.2006 0)
      (effects (font (size 1.27 1.27)) (justify right) hide)
    )
  )
  (global_label "GTX_TX4_N" (shape input) (at 360.68 136.525 0) (fields_autoplaced)
    (effects (font (size 1.27 1.27)) (justify left))
    (property "Intersheetrefs" "${INTERSHEET_REFS}" (at 373.1037 136.4456 0)
      (effects (font (size 1.27 1.27)) (justify left) hide)
    )
  )
  (global_label "EXT_ETH1_P" (shape input) (at 60.325 182.88 180) (fields_autoplaced)
    (effects (font (size 1.27 1.27)) (justify right))
    (property "Intersheetrefs" "${INTERSHEET_REFS}" (at 46.8127 182.8006 0)
      (effects (font (size 1.27 1.27)) (justify right) hide)
    )
  )
  (global_label "FMC_IO_2_P" (shape input) (at 97.79 208.28 0) (fields_autoplaced)
    (effects (font (size 1.27 1.27)) (justify left))
    (property "Intersheetrefs" "${INTERSHEET_REFS}" (at 111.2418 208.2006 0)
      (effects (font (size 1.27 1.27)) (justify left) hide)
    )
  )
  (global_label "12P0V" (shape input) (at 227.33 244.475 180) (fields_autoplaced)
    (effects (font (size 1.27 1.27)) (justify right))
    (property "Intersheetrefs" "${INTERSHEET_REFS}" (at 219.0187 244.5544 0)
      (effects (font (size 1.27 1.27)) (justify right) hide)
    )
  )
  (global_label "GTX_RX4_N" (shape input) (at 274.32 67.31 0) (fields_autoplaced)
    (effects (font (size 1.27 1.27)) (justify left))
    (property "Intersheetrefs" "${INTERSHEET_REFS}" (at 287.0461 67.2306 0)
      (effects (font (size 1.27 1.27)) (justify left) hide)
    )
  )
  (global_label "FMC_IO_20_P" (shape input) (at 60.325 92.71 180) (fields_autoplaced)
    (effects (font (size 1.27 1.27)) (justify right))
    (property "Intersheetrefs" "${INTERSHEET_REFS}" (at 46.8732 92.6306 0)
      (effects (font (size 1.27 1.27)) (justify right) hide)
    )
  )
  (global_label "FMC_IO_16_N" (shape input) (at 60.96 57.15 180) (fields_autoplaced)
    (effects (font (size 1.27 1.27)) (justify right))
    (property "Intersheetrefs" "${INTERSHEET_REFS}" (at 47.4477 57.0706 0)
      (effects (font (size 1.27 1.27)) (justify right) hide)
    )
  )
  (global_label "FMC_IO_20_N" (shape input) (at 60.325 95.25 180) (fields_autoplaced)
    (effects (font (size 1.27 1.27)) (justify right))
    (property "Intersheetrefs" "${INTERSHEET_REFS}" (at 46.8127 95.1706 0)
      (effects (font (size 1.27 1.27)) (justify right) hide)
    )
  )
  (global_label "GTX_RX0_N" (shape input) (at 191.77 184.785 0) (fields_autoplaced)
    (effects (font (size 1.27 1.27)) (justify left))
    (property "Intersheetrefs" "${INTERSHEET_REFS}" (at 204.4961 184.7056 0)
      (effects (font (size 1.27 1.27)) (justify left) hide)
    )
  )
  (global_label "EXT_ETH4_N" (shape input) (at 97.79 198.12 0) (fields_autoplaced)
    (effects (font (size 1.27 1.27)) (justify left))
    (property "Intersheetrefs" "${INTERSHEET_REFS}" (at 111.3628 198.0406 0)
      (effects (font (size 1.27 1.27)) (justify left) hide)
    )
  )
  (global_label "FMC_IO_25" (shape input) (at 60.325 99.06 180) (fields_autoplaced)
    (effects (font (size 1.27 1.27)) (justify right))
    (property "Intersheetrefs" "${INTERSHEET_REFS}" (at 47.9013 99.1394 0)
      (effects (font (size 1.27 1.27)) (justify right) hide)
    )
  )
  (global_label "FMC_IO_12_P" (shape input) (at 97.79 86.36 0) (fields_autoplaced)
    (effects (font (size 1.27 1.27)) (justify left))
    (property "Intersheetrefs" "${INTERSHEET_REFS}" (at 111.2418 86.2806 0)
      (effects (font (size 1.27 1.27)) (justify left) hide)
    )
  )
  (global_label "AUX_JTAG_RST" (shape input) (at 152.4 241.935 180) (fields_autoplaced)
    (effects (font (size 1.27 1.27)) (justify right))
    (property "Intersheetrefs" "${INTERSHEET_REFS}" (at 300.99 327.025 0)
      (effects (font (size 1.27 1.27)) hide)
    )
  )
  (global_label "FMC_IO_17_N" (shape input) (at 60.96 76.2 180) (fields_autoplaced)
    (effects (font (size 1.27 1.27)) (justify right))
    (property "Intersheetrefs" "${INTERSHEET_REFS}" (at 47.4477 76.1206 0)
      (effects (font (size 1.27 1.27)) (justify right) hide)
    )
  )
  (global_label "FMC_IO_21_P" (shape input) (at 60.96 60.96 180) (fields_autoplaced)
    (effects (font (size 1.27 1.27)) (justify right))
    (property "Intersheetrefs" "${INTERSHEET_REFS}" (at 47.5082 60.8806 0)
      (effects (font (size 1.27 1.27)) (justify right) hide)
    )
  )
  (global_label "FMC_IO_1_P" (shape input) (at 97.79 214.63 0) (fields_autoplaced)
    (effects (font (size 1.27 1.27)) (justify left))
    (property "Intersheetrefs" "${INTERSHEET_REFS}" (at 111.2418 214.5506 0)
      (effects (font (size 1.27 1.27)) (justify left) hide)
    )
  )
  (global_label "GTX_RX4_P" (shape input) (at 274.32 64.77 0) (fields_autoplaced)
    (effects (font (size 1.27 1.27)) (justify left))
    (property "Intersheetrefs" "${INTERSHEET_REFS}" (at 286.9856 64.6906 0)
      (effects (font (size 1.27 1.27)) (justify left) hide)
    )
  )
  (global_label "3V3_SYS" (shape input) (at 145.415 169.545 180) (fields_autoplaced)
    (effects (font (size 1.27 1.27)) (justify right))
    (property "Intersheetrefs" "${INTERSHEET_REFS}" (at 99.06 244.475 0)
      (effects (font (size 1.27 1.27)) hide)
    )
  )
  (global_label "FMC_IO_9_P" (shape input) (at 97.79 233.68 0) (fields_autoplaced)
    (effects (font (size 1.27 1.27)) (justify left))
    (property "Intersheetrefs" "${INTERSHEET_REFS}" (at 111.2418 233.6006 0)
      (effects (font (size 1.27 1.27)) (justify left) hide)
    )
  )
  (global_label "FMC_IO_12_N" (shape input) (at 97.79 88.9 0) (fields_autoplaced)
    (effects (font (size 1.27 1.27)) (justify left))
    (property "Intersheetrefs" "${INTERSHEET_REFS}" (at 111.3023 88.8206 0)
      (effects (font (size 1.27 1.27)) (justify left) hide)
    )
  )
  (global_label "FMC_IO_4_P" (shape input) (at 59.69 201.93 180) (fields_autoplaced)
    (effects (font (size 1.27 1.27)) (justify right))
    (property "Intersheetrefs" "${INTERSHEET_REFS}" (at 46.2382 201.8506 0)
      (effects (font (size 1.27 1.27)) (justify right) hide)
    )
  )
  (global_label "FMC_IO_19_N" (shape input) (at 59.563 217.17 180) (fields_autoplaced)
    (effects (font (size 1.27 1.27)) (justify right))
    (property "Intersheetrefs" "${INTERSHEET_REFS}" (at 46.0507 217.0906 0)
      (effects (font (size 1.27 1.27)) (justify right) hide)
    )
  )
  (global_label "GTX_TX6_P" (shape input) (at 360.68 154.305 0) (fields_autoplaced)
    (effects (font (size 1.27 1.27)) (justify left))
    (property "Intersheetrefs" "${INTERSHEET_REFS}" (at 373.0432 154.2256 0)
      (effects (font (size 1.27 1.27)) (justify left) hide)
    )
  )
  (global_label "GTX_TX2_P" (shape input) (at 360.68 113.665 0) (fields_autoplaced)
    (effects (font (size 1.27 1.27)) (justify left))
    (property "Intersheetrefs" "${INTERSHEET_REFS}" (at 373.0432 113.5856 0)
      (effects (font (size 1.27 1.27)) (justify left) hide)
    )
  )
  (global_label "FMC_IO_10_N" (shape input) (at 59.69 223.52 180) (fields_autoplaced)
    (effects (font (size 1.27 1.27)) (justify right))
    (property "Intersheetrefs" "${INTERSHEET_REFS}" (at 46.1777 223.4406 0)
      (effects (font (size 1.27 1.27)) (justify right) hide)
    )
  )
  (global_label "GTR_REFCLK2_C_N" (shape input) (at 357.505 66.675 0) (fields_autoplaced)
    (effects (font (size 1.27 1.27)) (justify left))
    (property "Intersheetrefs" "${INTERSHEET_REFS}" (at 377.1254 66.5956 0)
      (effects (font (size 1.27 1.27)) (justify left) hide)
    )
  )
  (global_label "GTX_TX5_N" (shape input) (at 360.68 146.685 0) (fields_autoplaced)
    (effects (font (size 1.27 1.27)) (justify left))
    (property "Intersheetrefs" "${INTERSHEET_REFS}" (at 373.1037 146.6056 0)
      (effects (font (size 1.27 1.27)) (justify left) hide)
    )
  )
  (global_label "GTX_RX5_N" (shape input) (at 274.32 73.66 0) (fields_autoplaced)
    (effects (font (size 1.27 1.27)) (justify left))
    (property "Intersheetrefs" "${INTERSHEET_REFS}" (at 287.0461 73.5806 0)
      (effects (font (size 1.27 1.27)) (justify left) hide)
    )
  )
  (global_label "EXT_ETH2_P" (shape input) (at 97.79 189.23 0) (fields_autoplaced)
    (effects (font (size 1.27 1.27)) (justify left))
    (property "Intersheetrefs" "${INTERSHEET_REFS}" (at 111.3023 189.1506 0)
      (effects (font (size 1.27 1.27)) (justify left) hide)
    )
  )
  (global_label "EXT_ETH3_P" (shape input) (at 60.325 189.23 180) (fields_autoplaced)
    (effects (font (size 1.27 1.27)) (justify right))
    (property "Intersheetrefs" "${INTERSHEET_REFS}" (at 46.8127 189.1506 0)
      (effects (font (size 1.27 1.27)) (justify right) hide)
    )
  )
  (global_label "GTX_TX7_N" (shape input) (at 360.68 167.005 0) (fields_autoplaced)
    (effects (font (size 1.27 1.27)) (justify left))
    (property "Intersheetrefs" "${INTERSHEET_REFS}" (at 373.1037 166.9256 0)
      (effects (font (size 1.27 1.27)) (justify left) hide)
    )
  )
  (global_label "GTX_TX7_P" (shape input) (at 360.68 164.465 0) (fields_autoplaced)
    (effects (font (size 1.27 1.27)) (justify left))
    (property "Intersheetrefs" "${INTERSHEET_REFS}" (at 373.0432 164.3856 0)
      (effects (font (size 1.27 1.27)) (justify left) hide)
    )
  )
  (global_label "FMC_IO_14_N" (shape input) (at 97.79 95.25 0) (fields_autoplaced)
    (effects (font (size 1.27 1.27)) (justify left))
    (property "Intersheetrefs" "${INTERSHEET_REFS}" (at 111.3023 95.1706 0)
      (effects (font (size 1.27 1.27)) (justify left) hide)
    )
  )
  (global_label "GTX_TX1_N" (shape input) (at 360.68 106.045 0) (fields_autoplaced)
    (effects (font (size 1.27 1.27)) (justify left))
    (property "Intersheetrefs" "${INTERSHEET_REFS}" (at 373.1037 105.9656 0)
      (effects (font (size 1.27 1.27)) (justify left) hide)
    )
  )
  (global_label "GTX_TX0_N" (shape input) (at 360.68 95.885 0) (fields_autoplaced)
    (effects (font (size 1.27 1.27)) (justify left))
    (property "Intersheetrefs" "${INTERSHEET_REFS}" (at 373.1037 95.8056 0)
      (effects (font (size 1.27 1.27)) (justify left) hide)
    )
  )
  (global_label "GTR_REFCLK2_C_P" (shape input) (at 357.505 64.135 0) (fields_autoplaced)
    (effects (font (size 1.27 1.27)) (justify left))
    (property "Intersheetrefs" "${INTERSHEET_REFS}" (at 377.0649 64.0556 0)
      (effects (font (size 1.27 1.27)) (justify left) hide)
    )
  )
  (global_label "GTX_TX3_N" (shape input) (at 360.68 126.365 0) (fields_autoplaced)
    (effects (font (size 1.27 1.27)) (justify left))
    (property "Intersheetrefs" "${INTERSHEET_REFS}" (at 373.1037 126.2856 0)
      (effects (font (size 1.27 1.27)) (justify left) hide)
    )
  )
  (global_label "FMC_IO_23_P" (shape input) (at 98.425 67.31 0) (fields_autoplaced)
    (effects (font (size 1.27 1.27)) (justify left))
    (property "Intersheetrefs" "${INTERSHEET_REFS}" (at 111.8768 67.2306 0)
      (effects (font (size 1.27 1.27)) (justify left) hide)
    )
  )
  (global_label "PRSNT_M2C" (shape input) (at 43.815 172.72 180) (fields_autoplaced)
    (effects (font (size 1.27 1.27)) (justify right))
    (property "Intersheetrefs" "${INTERSHEET_REFS}" (at 30.5446 172.6406 0)
      (effects (font (size 1.27 1.27)) (justify right) hide)
    )
  )
  (global_label "3V3_SYS" (shape input) (at 137.795 182.245 180) (fields_autoplaced)
    (effects (font (size 1.27 1.27)) (justify right))
    (property "Intersheetrefs" "${INTERSHEET_REFS}" (at 91.44 257.175 0)
      (effects (font (size 1.27 1.27)) hide)
    )
  )
  (global_label "~{PERST}" (shape input) (at 137.795 189.865 180) (fields_autoplaced)
    (effects (font (size 1.27 1.27)) (justify right))
    (property "Intersheetrefs" "${INTERSHEET_REFS}" (at 129.6046 189.7856 0)
      (effects (font (size 1.27 1.27)) (justify right) hide)
    )
  )
  (global_label "GTX_RX1_N" (shape input) (at 274.32 48.26 0) (fields_autoplaced)
    (effects (font (size 1.27 1.27)) (justify left))
    (property "Intersheetrefs" "${INTERSHEET_REFS}" (at 287.0461 48.1806 0)
      (effects (font (size 1.27 1.27)) (justify left) hide)
    )
  )
  (global_label "AUX_JTAG_TMS" (shape input) (at 152.4 239.395 180) (fields_autoplaced)
    (effects (font (size 1.27 1.27)) (justify right))
    (property "Intersheetrefs" "${INTERSHEET_REFS}" (at 300.99 319.405 0)
      (effects (font (size 1.27 1.27)) hide)
    )
  )
  (global_label "GTX_TX0_P" (shape input) (at 360.68 93.345 0) (fields_autoplaced)
    (effects (font (size 1.27 1.27)) (justify left))
    (property "Intersheetrefs" "${INTERSHEET_REFS}" (at 373.0432 93.2656 0)
      (effects (font (size 1.27 1.27)) (justify left) hide)
    )
  )
  (global_label "FMC_IO_24_N" (shape input) (at 97.79 101.6 0) (fields_autoplaced)
    (effects (font (size 1.27 1.27)) (justify left))
    (property "Intersheetrefs" "${INTERSHEET_REFS}" (at 111.3023 101.5206 0)
      (effects (font (size 1.27 1.27)) (justify left) hide)
    )
  )
  (global_label "GTX_RX7_N" (shape input) (at 234.315 60.96 180) (fields_autoplaced)
    (effects (font (size 1.27 1.27)) (justify right))
    (property "Intersheetrefs" "${INTERSHEET_REFS}" (at 221.5889 60.8806 0)
      (effects (font (size 1.27 1.27)) (justify right) hide)
    )
  )
  (global_label "GTX_RX5_P" (shape input) (at 274.32 71.12 0) (fields_autoplaced)
    (effects (font (size 1.27 1.27)) (justify left))
    (property "Intersheetrefs" "${INTERSHEET_REFS}" (at 286.9856 71.0406 0)
      (effects (font (size 1.27 1.27)) (justify left) hide)
    )
  )
  (global_label "GTX_RX3_P" (shape input) (at 274.32 58.42 0) (fields_autoplaced)
    (effects (font (size 1.27 1.27)) (justify left))
    (property "Intersheetrefs" "${INTERSHEET_REFS}" (at 286.9856 58.3406 0)
      (effects (font (size 1.27 1.27)) (justify left) hide)
    )
  )
  (global_label "FMC_SCL_3V3" (shape input) (at 207.645 226.695 0) (fields_autoplaced)
    (effects (font (size 1.27 1.27)) (justify left))
    (property "Intersheetrefs" "${INTERSHEET_REFS}" (at 222.7297 226.7744 0)
      (effects (font (size 1.27 1.27)) (justify left) hide)
    )
  )
  (global_label "GTX_TX5_P" (shape input) (at 360.68 144.145 0) (fields_autoplaced)
    (effects (font (size 1.27 1.27)) (justify left))
    (property "Intersheetrefs" "${INTERSHEET_REFS}" (at 373.0432 144.0656 0)
      (effects (font (size 1.27 1.27)) (justify left) hide)
    )
  )
  (global_label "GTX_TX6_N" (shape input) (at 360.68 156.845 0) (fields_autoplaced)
    (effects (font (size 1.27 1.27)) (justify left))
    (property "Intersheetrefs" "${INTERSHEET_REFS}" (at 373.1037 156.7656 0)
      (effects (font (size 1.27 1.27)) (justify left) hide)
    )
  )
  (global_label "FMC_IO_11_P" (shape input) (at 60.325 86.36 180) (fields_autoplaced)
    (effects (font (size 1.27 1.27)) (justify right))
    (property "Intersheetrefs" "${INTERSHEET_REFS}" (at 46.8732 86.2806 0)
      (effects (font (size 1.27 1.27)) (justify right) hide)
    )
  )
  (global_label "3V3_SYS" (shape input) (at 207.645 217.805 0) (fields_autoplaced)
    (effects (font (size 1.27 1.27)) (justify left))
    (property "Intersheetrefs" "${INTERSHEET_REFS}" (at 534.67 -10.16 0)
      (effects (font (size 1.27 1.27)) (justify left) hide)
    )
  )
  (global_label "CLK_DIR" (shape input) (at 234.315 39.37 180) (fields_autoplaced)
    (effects (font (size 1.27 1.27)) (justify right))
    (property "Intersheetrefs" "${INTERSHEET_REFS}" (at 224.3103 39.2906 0)
      (effects (font (size 1.27 1.27)) (justify right) hide)
    )
  )
  (global_label "FMC_IO_6_P" (shape input) (at 97.79 220.98 0) (fields_autoplaced)
    (effects (font (size 1.27 1.27)) (justify left))
    (property "Intersheetrefs" "${INTERSHEET_REFS}" (at 111.2418 220.9006 0)
      (effects (font (size 1.27 1.27)) (justify left) hide)
    )
  )
  (global_label "3V3_SYS" (shape input) (at 43.815 161.925 180) (fields_autoplaced)
    (effects (font (size 1.27 1.27)) (justify right))
    (property "Intersheetrefs" "${INTERSHEET_REFS}" (at -2.54 236.855 0)
      (effects (font (size 1.27 1.27)) hide)
    )
  )
  (global_label "FMC_IO_19_P" (shape input) (at 59.563 214.63 180) (fields_autoplaced)
    (effects (font (size 1.27 1.27)) (justify right))
    (property "Intersheetrefs" "${INTERSHEET_REFS}" (at 46.1112 214.5506 0)
      (effects (font (size 1.27 1.27)) (justify right) hide)
    )
  )
  (global_label "AUX_JTAG_TDO" (shape input) (at 152.4 231.775 180) (fields_autoplaced)
    (effects (font (size 1.27 1.27)) (justify right))
    (property "Intersheetrefs" "${INTERSHEET_REFS}" (at 300.99 309.245 0)
      (effects (font (size 1.27 1.27)) hide)
    )
  )
  (global_label "FMC_IO_24_P" (shape input) (at 97.79 99.06 0) (fields_autoplaced)
    (effects (font (size 1.27 1.27)) (justify left))
    (property "Intersheetrefs" "${INTERSHEET_REFS}" (at 111.2418 98.9806 0)
      (effects (font (size 1.27 1.27)) (justify left) hide)
    )
  )
  (global_label "FMC_IO_9_N" (shape input) (at 97.79 236.22 0) (fields_autoplaced)
    (effects (font (size 1.27 1.27)) (justify left))
    (property "Intersheetrefs" "${INTERSHEET_REFS}" (at 111.3023 236.1406 0)
      (effects (font (size 1.27 1.27)) (justify left) hide)
    )
  )
  (global_label "FMC_IO_14_P" (shape input) (at 97.79 92.71 0) (fields_autoplaced)
    (effects (font (size 1.27 1.27)) (justify left))
    (property "Intersheetrefs" "${INTERSHEET_REFS}" (at 111.2418 92.6306 0)
      (effects (font (size 1.27 1.27)) (justify left) hide)
    )
  )
  (global_label "GTR_REFCLK1_C_P" (shape input) (at 357.505 53.975 0) (fields_autoplaced)
    (effects (font (size 1.27 1.27)) (justify left))
    (property "Intersheetrefs" "${INTERSHEET_REFS}" (at 377.0649 53.8956 0)
      (effects (font (size 1.27 1.27)) (justify left) hide)
    )
  )
  (global_label "FMC_SDA_3V3" (shape input) (at 207.645 229.235 0) (fields_autoplaced)
    (effects (font (size 1.27 1.27)) (justify left))
    (property "Intersheetrefs" "${INTERSHEET_REFS}" (at 222.7902 229.3144 0)
      (effects (font (size 1.27 1.27)) (justify left) hide)
    )
  )
  (global_label "FMC_IO_23_N" (shape input) (at 98.425 69.85 0) (fields_autoplaced)
    (effects (font (size 1.27 1.27)) (justify left))
    (property "Intersheetrefs" "${INTERSHEET_REFS}" (at 111.9373 69.7706 0)
      (effects (font (size 1.27 1.27)) (justify left) hide)
    )
  )
  (global_label "3V3_SYS" (shape input) (at 191.77 252.095 0) (fields_autoplaced)
    (effects (font (size 1.27 1.27)) (justify left))
    (property "Intersheetrefs" "${INTERSHEET_REFS}" (at 238.125 177.165 0)
      (effects (font (size 1.27 1.27)) hide)
    )
  )
  (global_label "GTR_REFCLK0_C_N" (shape input) (at 357.505 46.99 0) (fields_autoplaced)
    (effects (font (size 1.27 1.27)) (justify left))
    (property "Intersheetrefs" "${INTERSHEET_REFS}" (at 377.1254 46.9106 0)
      (effects (font (size 1.27 1.27)) (justify left) hide)
    )
  )
  (global_label "FMC_IO_1_N" (shape input) (at 97.79 217.17 0) (fields_autoplaced)
    (effects (font (size 1.27 1.27)) (justify left))
    (property "Intersheetrefs" "${INTERSHEET_REFS}" (at 111.3023 217.0906 0)
      (effects (font (size 1.27 1.27)) (justify left) hide)
    )
  )
  (global_label "EXT_LED_LINK" (shape input) (at 98.425 182.88 0) (fields_autoplaced)
    (effects (font (size 1.27 1.27)) (justify left))
    (property "Intersheetrefs" "${INTERSHEET_REFS}" (at 113.6911 182.8006 0)
      (effects (font (size 1.27 1.27)) (justify left) hide)
    )
  )
  (global_label "GTX_TX4_P" (shape input) (at 360.68 133.985 0) (fields_autoplaced)
    (effects (font (size 1.27 1.27)) (justify left))
    (property "Intersheetrefs" "${INTERSHEET_REFS}" (at 373.0432 133.9056 0)
      (effects (font (size 1.27 1.27)) (justify left) hide)
    )
  )
  (global_label "GTR_REFCLK1_C_N" (shape input) (at 357.505 56.515 0) (fields_autoplaced)
    (effects (font (size 1.27 1.27)) (justify left))
    (property "Intersheetrefs" "${INTERSHEET_REFS}" (at 377.1254 56.4356 0)
      (effects (font (size 1.27 1.27)) (justify left) hide)
    )
  )
  (global_label "EXT_LED_SPD" (shape input) (at 98.425 185.42 0) (fields_autoplaced)
    (effects (font (size 1.27 1.27)) (justify left))
    (property "Intersheetrefs" "${INTERSHEET_REFS}" (at 113.2073 185.3406 0)
      (effects (font (size 1.27 1.27)) (justify left) hide)
    )
  )
  (global_label "GTX_RX6_N" (shape input) (at 234.315 67.31 180) (fields_autoplaced)
    (effects (font (size 1.27 1.27)) (justify right))
    (property "Intersheetrefs" "${INTERSHEET_REFS}" (at 221.5889 67.2306 0)
      (effects (font (size 1.27 1.27)) (justify right) hide)
    )
  )
  (global_label "FMC_IO_18_P" (shape input) (at 98.425 60.96 0) (fields_autoplaced)
    (effects (font (size 1.27 1.27)) (justify left))
    (property "Intersheetrefs" "${INTERSHEET_REFS}" (at 111.8768 60.8806 0)
      (effects (font (size 1.27 1.27)) (justify left) hide)
    )
  )
  (global_label "FMC_IO_5_N" (shape input) (at 97.79 82.55 0) (fields_autoplaced)
    (effects (font (size 1.27 1.27)) (justify left))
    (property "Intersheetrefs" "${INTERSHEET_REFS}" (at 111.3023 82.4706 0)
      (effects (font (size 1.27 1.27)) (justify left) hide)
    )
  )
  (global_label "FMC_IO_17_P" (shape input) (at 60.96 73.66 180) (fields_autoplaced)
    (effects (font (size 1.27 1.27)) (justify right))
    (property "Intersheetrefs" "${INTERSHEET_REFS}" (at 47.5082 73.5806 0)
      (effects (font (size 1.27 1.27)) (justify right) hide)
    )
  )
  (global_label "GTX_TX2_N" (shape input) (at 360.68 116.205 0) (fields_autoplaced)
    (effects (font (size 1.27 1.27)) (justify left))
    (property "Intersheetrefs" "${INTERSHEET_REFS}" (at 373.1037 116.1256 0)
      (effects (font (size 1.27 1.27)) (justify left) hide)
    )
  )
  (global_label "GTX_RX1_P" (shape input) (at 274.32 45.72 0) (fields_autoplaced)
    (effects (font (size 1.27 1.27)) (justify left))
    (property "Intersheetrefs" "${INTERSHEET_REFS}" (at 286.9856 45.6406 0)
      (effects (font (size 1.27 1.27)) (justify left) hide)
    )
  )
  (global_label "AUX_JTAG_TDI" (shape input) (at 152.4 229.235 180) (fields_autoplaced)
    (effects (font (size 1.27 1.27)) (justify right))
    (property "Intersheetrefs" "${INTERSHEET_REFS}" (at 300.99 304.165 0)
      (effects (font (size 1.27 1.27)) hide)
    )
  )
  (global_label "12P0V" (shape input) (at 205.105 248.285 0) (fields_autoplaced)
    (effects (font (size 1.27 1.27)) (justify left))
    (property "Intersheetrefs" "${INTERSHEET_REFS}" (at 213.4163 248.2056 0)
      (effects (font (size 1.27 1.27)) (justify left) hide)
    )
  )
  (global_label "EXT_ETH4_P" (shape input) (at 97.79 195.58 0) (fields_autoplaced)
    (effects (font (size 1.27 1.27)) (justify left))
    (property "Intersheetrefs" "${INTERSHEET_REFS}" (at 111.3023 195.5006 0)
      (effects (font (size 1.27 1.27)) (justify left) hide)
    )
  )
  (global_label "GTX_RX0_P" (shape input) (at 191.77 182.245 0) (fields_autoplaced)
    (effects (font (size 1.27 1.27)) (justify left))
    (property "Intersheetrefs" "${INTERSHEET_REFS}" (at 204.4356 182.1656 0)
      (effects (font (size 1.27 1.27)) (justify left) hide)
    )
  )
  (global_label "FMC_IO_3_N" (shape input) (at 59.69 210.82 180) (fields_autoplaced)
    (effects (font (size 1.27 1.27)) (justify right))
    (property "Intersheetrefs" "${INTERSHEET_REFS}" (at 46.1777 210.7406 0)
      (effects (font (size 1.27 1.27)) (justify right) hide)
    )
  )
  (global_label "GTX_RX7_P" (shape input) (at 234.315 58.42 180) (fields_autoplaced)
    (effects (font (size 1.27 1.27)) (justify right))
    (property "Intersheetrefs" "${INTERSHEET_REFS}" (at 221.6494 58.3406 0)
      (effects (font (size 1.27 1.27)) (justify right) hide)
    )
  )
  (global_label "FMC_IO_16_P" (shape input) (at 60.96 54.61 180) (fields_autoplaced)
    (effects (font (size 1.27 1.27)) (justify right))
    (property "Intersheetrefs" "${INTERSHEET_REFS}" (at 47.5082 54.5306 0)
      (effects (font (size 1.27 1.27)) (justify right) hide)
    )
  )
  (global_label "GTR_REFCLK3_C_N" (shape input) (at 357.505 76.835 0) (fields_autoplaced)
    (effects (font (size 1.27 1.27)) (justify left))
    (property "Intersheetrefs" "${INTERSHEET_REFS}" (at 377.1254 76.7556 0)
      (effects (font (size 1.27 1.27)) (justify left) hide)
    )
  )
  (global_label "VIN" (shape input) (at 205.105 245.11 0) (fields_autoplaced)
    (effects (font (size 1.27 1.27)) (justify left))
    (property "Intersheetrefs" "${INTERSHEET_REFS}" (at 210.453 245.0306 0)
      (effects (font (size 1.27 1.27)) (justify left) hide)
    )
  )

  (symbol (lib_id "antmicroResistors0402:R_33R_0402") (at 344.17 56.515 0) (unit 1)
    (in_bom yes) (on_board yes) (dnp no)
    (property "Reference" "R149" (at 341.63 55.245 0)
      (effects (font (size 1.524 1.524)))
    )
    (property "Value" "R_33R_0402" (at 364.49 69.215 0)
      (effects (font (size 1.27 1.27) (thickness 0.15)) (justify left bottom) hide)
    )
    (property "Footprint" "antmicro-footprints:R_0402_1005Metric" (at 364.49 71.755 0)
      (effects (font (size 1.27 1.27) (thickness 0.15)) (justify left bottom) hide)
    )
    (property "Datasheet" "https://www.bourns.com/docs/product-datasheets/cr.pdf" (at 364.49 74.295 0)
      (effects (font (size 1.27 1.27) (thickness 0.15)) (justify left bottom) hide)
    )
    (property "Manufacturer" "Bourns" (at 364.49 79.375 0)
      (effects (font (size 1.27 1.27) (thickness 0.15)) (justify left bottom) hide)
    )
    (property "MPN" "CR0402-FX-33R0GLF" (at 364.49 76.835 0)
      (effects (font (size 1.27 1.27) (thickness 0.15)) (justify left bottom) hide)
    )
    (property "Val" "33R" (at 351.155 55.245 0)
      (effects (font (size 1.27 1.27) (thickness 0.15)))
    )
    (property "License" "Apache-2.0" (at 364.49 81.915 0)
      (effects (font (size 1.27 1.27) (thickness 0.15)) (justify left bottom) hide)
    )
    (property "Author" "Antmicro" (at 364.49 84.455 0)
      (effects (font (size 1.27 1.27) (thickness 0.15)) (justify left bottom) hide)
    )
    (property "Tolerance" "1%" (at 364.49 66.675 0)
      (effects (font (size 1.27 1.27)) (justify left bottom) hide)
    )
    (pin "1")
    (pin "2")
    (instances
      (project "data-center-rdimm-ddr4-tester"
        (path ""
          (reference "R149") (unit 1)
        )
      )
    )
  )

  (symbol (lib_id "antmicropower:GND") (at 238.76 123.825 0) (unit 1)
    (in_bom yes) (on_board yes) (dnp no) (fields_autoplaced)
    (property "Reference" "#PWR0348" (at 238.76 130.175 0)
      (effects (font (size 1.27 1.27)) hide)
    )
    (property "Value" "GND" (at 238.76 127.635 0)
      (effects (font (size 1.27 1.27)))
    )
    (property "Footprint" "" (at 238.76 123.825 0)
      (effects (font (size 1.27 1.27)) hide)
    )
    (property "Datasheet" "" (at 238.76 123.825 0)
      (effects (font (size 1.27 1.27)) hide)
    )
    (property "Author" "Antmicro" (at 247.65 131.445 0)
      (effects (font (size 1.27 1.27) (thickness 0.15)) (justify left bottom) hide)
    )
    (property "License" "Apache-2.0" (at 247.65 133.985 0)
      (effects (font (size 1.27 1.27) (thickness 0.15)) (justify left bottom) hide)
    )
    (pin "1")
    (instances
      (project "data-center-rdimm-ddr4-tester"
        (path ""
          (reference "#PWR0348") (unit 1)
        )
      )
    )
  )

  (symbol (lib_id "antmicroCapacitors0402:C_100n_0402") (at 337.82 133.985 0) (unit 1)
    (in_bom yes) (on_board yes) (dnp no)
    (property "Reference" "C267" (at 336.55 132.715 0)
      (effects (font (size 1.524 1.524)))
    )
    (property "Value" "C_100n_0402" (at 358.14 144.145 0)
      (effects (font (size 1.27 1.27) (thickness 0.15)) (justify left bottom) hide)
    )
    (property "Footprint" "antmicro-footprints:C_0402_1005Metric" (at 358.14 146.685 0)
      (effects (font (size 1.27 1.27) (thickness 0.15)) (justify left bottom) hide)
    )
    (property "Datasheet" "https://search.murata.co.jp/Ceramy/image/img/A01X/G101/ENG/GRM155R61H104KE14-01.pdf" (at 358.14 149.225 0)
      (effects (font (size 1.27 1.27) (thickness 0.15)) (justify left bottom) hide)
    )
    (property "Manufacturer" "Murata" (at 358.14 154.305 0)
      (effects (font (size 1.27 1.27) (thickness 0.15)) (justify left bottom) hide)
    )
    (property "MPN" "GRM155R61H104KE14D" (at 358.14 151.765 0)
      (effects (font (size 1.27 1.27) (thickness 0.15)) (justify left bottom) hide)
    )
    (property "Val" "100n" (at 343.535 132.715 0)
      (effects (font (size 1.27 1.27) (thickness 0.15)))
    )
    (property "License" "Apache-2.0" (at 358.14 156.845 0)
      (effects (font (size 1.27 1.27) (thickness 0.15)) (justify left bottom) hide)
    )
    (property "Author" "Antmicro" (at 358.14 159.385 0)
      (effects (font (size 1.27 1.27) (thickness 0.15)) (justify left bottom) hide)
    )
    (property "Voltage" "50V" (at 358.14 161.925 0)
      (effects (font (size 1.27 1.27)) (justify left bottom) hide)
    )
    (property "Dielectric" "X5R" (at 358.14 164.465 0)
      (effects (font (size 1.27 1.27)) (justify left bottom) hide)
    )
    (pin "1")
    (pin "2")
    (instances
      (project "data-center-rdimm-ddr4-tester"
        (path ""
          (reference "C267") (unit 1)
        )
      )
    )
  )

  (symbol (lib_id "antmicroTestPoints:TP_0.75mm_SMD") (at 62.865 170.18 180) (unit 1)
    (in_bom yes) (on_board yes) (dnp no)
    (property "Reference" "TP16" (at 55.88 170.18 0)
      (effects (font (size 1.27 1.27)))
    )
    (property "Value" "TP_0.75mm_SMD" (at 47.625 162.56 0)
      (effects (font (size 1.27 1.27) (thickness 0.15)) (justify left bottom) hide)
    )
    (property "Footprint" "antmicro-footprints:TP_SMD_0.75mm" (at 47.625 160.02 0)
      (effects (font (size 1.27 1.27) (thickness 0.15)) (justify left bottom) hide)
    )
    (property "Datasheet" "" (at 47.625 157.48 0)
      (effects (font (size 1.27 1.27) (thickness 0.15)) (justify left bottom) hide)
    )
    (property "MPN" "" (at 62.865 170.18 0)
      (effects (font (size 1.27 1.27)) hide)
    )
    (property "Manufacturer" "" (at 62.865 170.18 0)
      (effects (font (size 1.27 1.27)) hide)
    )
    (property "Author" "Antmicro" (at 47.625 154.94 0)
      (effects (font (size 1.27 1.27) (thickness 0.15)) (justify left bottom) hide)
    )
    (property "License" "Apache-2.0" (at 47.625 152.4 0)
      (effects (font (size 1.27 1.27) (thickness 0.15)) (justify left bottom) hide)
    )
    (pin "1")
    (instances
      (project "data-center-rdimm-ddr4-tester"
        (path ""
          (reference "TP16") (unit 1)
        )
      )
    )
  )

  (symbol (lib_id "antmicroTestPoints:TP_0.75mm_SMD") (at 61.595 41.91 180) (unit 1)
    (in_bom yes) (on_board yes) (dnp no) (fields_autoplaced)
    (property "Reference" "TP15" (at 58.42 38.1 0)
      (effects (font (size 1.27 1.27)))
    )
    (property "Value" "TP_0.75mm_SMD" (at 46.355 34.29 0)
      (effects (font (size 1.27 1.27) (thickness 0.15)) (justify left bottom) hide)
    )
    (property "Footprint" "antmicro-footprints:TP_SMD_0.75mm" (at 46.355 31.75 0)
      (effects (font (size 1.27 1.27) (thickness 0.15)) (justify left bottom) hide)
    )
    (property "Datasheet" "" (at 46.355 29.21 0)
      (effects (font (size 1.27 1.27) (thickness 0.15)) (justify left bottom) hide)
    )
    (property "MPN" "" (at 61.595 41.91 0)
      (effects (font (size 1.27 1.27)) hide)
    )
    (property "Manufacturer" "" (at 61.595 41.91 0)
      (effects (font (size 1.27 1.27)) hide)
    )
    (property "Author" "Antmicro" (at 46.355 26.67 0)
      (effects (font (size 1.27 1.27) (thickness 0.15)) (justify left bottom) hide)
    )
    (property "License" "Apache-2.0" (at 46.355 24.13 0)
      (effects (font (size 1.27 1.27) (thickness 0.15)) (justify left bottom) hide)
    )
    (pin "1")
    (instances
      (project "data-center-rdimm-ddr4-tester"
        (path ""
          (reference "TP15") (unit 1)
        )
      )
    )
  )

  (symbol (lib_id "antmicroResistors0402:R_10k_0402") (at 46.99 168.91 90) (unit 1)
    (in_bom yes) (on_board yes) (dnp no) (fields_autoplaced)
    (property "Reference" "R208" (at 49.53 165.1 90)
      (effects (font (size 1.524 1.524)) (justify right))
    )
    (property "Value" "R_10k_0402" (at 59.69 148.59 0)
      (effects (font (size 1.27 1.27) (thickness 0.15)) (justify left bottom) hide)
    )
    (property "Footprint" "antmicro-footprints:R_0402_1005Metric" (at 62.23 148.59 0)
      (effects (font (size 1.27 1.27) (thickness 0.15)) (justify left bottom) hide)
    )
    (property "Datasheet" "https://www.bourns.com/docs/product-datasheets/cr.pdf" (at 64.77 148.59 0)
      (effects (font (size 1.27 1.27) (thickness 0.15)) (justify left bottom) hide)
    )
    (property "Manufacturer" "Bourns" (at 69.85 148.59 0)
      (effects (font (size 1.27 1.27) (thickness 0.15)) (justify left bottom) hide)
    )
    (property "MPN" "CR0402-FX-1002GLF" (at 67.31 148.59 0)
      (effects (font (size 1.27 1.27) (thickness 0.15)) (justify left bottom) hide)
    )
    (property "Val" "10k" (at 49.53 168.2749 90)
      (effects (font (size 1.27 1.27) (thickness 0.15)) (justify right))
    )
    (property "License" "Apache-2.0" (at 72.39 148.59 0)
      (effects (font (size 1.27 1.27) (thickness 0.15)) (justify left bottom) hide)
    )
    (property "Author" "Antmicro" (at 74.93 148.59 0)
      (effects (font (size 1.27 1.27) (thickness 0.15)) (justify left bottom) hide)
    )
    (property "Tolerance" "1%" (at 57.15 148.59 0)
      (effects (font (size 1.27 1.27)) (justify left bottom) hide)
    )
    (pin "1")
    (pin "2")
    (instances
      (project "data-center-rdimm-ddr4-tester"
        (path ""
          (reference "R208") (unit 1)
        )
      )
    )
  )

  (symbol (lib_id "antmicropower:GND") (at 62.23 126.365 0) (unit 1)
    (in_bom yes) (on_board yes) (dnp no) (fields_autoplaced)
    (property "Reference" "#PWR0351" (at 62.23 132.715 0)
      (effects (font (size 1.27 1.27)) hide)
    )
    (property "Value" "GND" (at 62.23 130.175 0)
      (effects (font (size 1.27 1.27)))
    )
    (property "Footprint" "" (at 62.23 126.365 0)
      (effects (font (size 1.27 1.27)) hide)
    )
    (property "Datasheet" "" (at 62.23 126.365 0)
      (effects (font (size 1.27 1.27)) hide)
    )
    (property "Author" "Antmicro" (at 71.12 133.985 0)
      (effects (font (size 1.27 1.27) (thickness 0.15)) (justify left bottom) hide)
    )
    (property "License" "Apache-2.0" (at 71.12 136.525 0)
      (effects (font (size 1.27 1.27) (thickness 0.15)) (justify left bottom) hide)
    )
    (pin "1")
    (instances
      (project "data-center-rdimm-ddr4-tester"
        (path ""
          (reference "#PWR0351") (unit 1)
        )
      )
    )
  )

  (symbol (lib_id "antmicroResistors0402:R_33R_0402") (at 344.17 44.45 0) (unit 1)
    (in_bom yes) (on_board yes) (dnp no)
    (property "Reference" "R210" (at 341.63 43.18 0)
      (effects (font (size 1.524 1.524)))
    )
    (property "Value" "R_33R_0402" (at 364.49 57.15 0)
      (effects (font (size 1.27 1.27) (thickness 0.15)) (justify left bottom) hide)
    )
    (property "Footprint" "antmicro-footprints:R_0402_1005Metric" (at 364.49 59.69 0)
      (effects (font (size 1.27 1.27) (thickness 0.15)) (justify left bottom) hide)
    )
    (property "Datasheet" "https://www.bourns.com/docs/product-datasheets/cr.pdf" (at 364.49 62.23 0)
      (effects (font (size 1.27 1.27) (thickness 0.15)) (justify left bottom) hide)
    )
    (property "Manufacturer" "Bourns" (at 364.49 67.31 0)
      (effects (font (size 1.27 1.27) (thickness 0.15)) (justify left bottom) hide)
    )
    (property "MPN" "CR0402-FX-33R0GLF" (at 364.49 64.77 0)
      (effects (font (size 1.27 1.27) (thickness 0.15)) (justify left bottom) hide)
    )
    (property "Val" "33R" (at 351.155 43.18 0)
      (effects (font (size 1.27 1.27) (thickness 0.15)))
    )
    (property "License" "Apache-2.0" (at 364.49 69.85 0)
      (effects (font (size 1.27 1.27) (thickness 0.15)) (justify left bottom) hide)
    )
    (property "Author" "Antmicro" (at 364.49 72.39 0)
      (effects (font (size 1.27 1.27) (thickness 0.15)) (justify left bottom) hide)
    )
    (property "Tolerance" "1%" (at 364.49 54.61 0)
      (effects (font (size 1.27 1.27)) (justify left bottom) hide)
    )
    (pin "1")
    (pin "2")
    (instances
      (project "data-center-rdimm-ddr4-tester"
        (path ""
          (reference "R210") (unit 1)
        )
      )
    )
  )

  (symbol (lib_id "antmicroFMCConnectors:ASP-134486-01") (at 64.135 170.18 0) (unit 2)
    (in_bom yes) (on_board yes) (dnp no) (fields_autoplaced)
    (property "Reference" "J5" (at 79.375 162.56 0)
      (effects (font (size 1.27 1.27)))
    )
    (property "Value" "ASP-134486-01" (at 79.375 165.1 0)
      (effects (font (size 1.27 1.27) (thickness 0.15)))
    )
    (property "Footprint" "antmicro-footprints:FMC_SAMTEC_ASP-134486-01" (at 109.855 181.61 0)
      (effects (font (size 1.27 1.27) (thickness 0.15)) (justify left bottom) hide)
    )
    (property "Datasheet" "https://suddendocs.samtec.com/prints/asp-134486-01-mkt.pdf?_gl=1*a2d3qa*_ga*MzYxMTM5My4xNjYzOTI3MDkz*_ga_3KFNZC07WW*MTY2NDIwMTUxMC4zLjAuMTY2NDIwMTUxMC42MC4wLjA." (at 109.855 184.15 0)
      (effects (font (size 1.27 1.27) (thickness 0.15)) (justify left bottom) hide)
    )
    (property "Manufacturer" "Samtec" (at 109.855 186.69 0)
      (effects (font (size 1.27 1.27) (thickness 0.15)) (justify left bottom) hide)
    )
    (property "MPN" "ASP-134486-01" (at 109.855 189.23 0)
      (effects (font (size 1.27 1.27) (thickness 0.15)) (justify left bottom) hide)
    )
    (property "Author" "Antmicro" (at 109.855 191.77 0)
      (effects (font (size 1.27 1.27) (thickness 0.15)) (justify left bottom) hide)
    )
    (property "License" "Apache-2.0" (at 109.855 194.31 0)
      (effects (font (size 1.27 1.27) (thickness 0.15)) (justify left bottom) hide)
    )
    (pin "J1")
    (pin "J10")
    (pin "J11")
    (pin "J12")
    (pin "J13")
    (pin "J14")
    (pin "J15")
    (pin "J16")
    (pin "J17")
    (pin "J18")
    (pin "J19")
    (pin "J2")
    (pin "J20")
    (pin "J21")
    (pin "J22")
    (pin "J23")
    (pin "J24")
    (pin "J25")
    (pin "J26")
    (pin "J27")
    (pin "J28")
    (pin "J29")
    (pin "J3")
    (pin "J30")
    (pin "J31")
    (pin "J32")
    (pin "J33")
    (pin "J34")
    (pin "J35")
    (pin "J36")
    (pin "J37")
    (pin "J38")
    (pin "J39")
    (pin "J4")
    (pin "J40")
    (pin "J5")
    (pin "J6")
    (pin "J7")
    (pin "J8")
    (pin "J9")
    (pin "K1")
    (pin "K10")
    (pin "K11")
    (pin "K12")
    (pin "K13")
    (pin "K14")
    (pin "K15")
    (pin "K16")
    (pin "K17")
    (pin "K18")
    (pin "K19")
    (pin "K2")
    (pin "K20")
    (pin "K21")
    (pin "K22")
    (pin "K23")
    (pin "K24")
    (pin "K25")
    (pin "K26")
    (pin "K27")
    (pin "K28")
    (pin "K29")
    (pin "K3")
    (pin "K30")
    (pin "K31")
    (pin "K32")
    (pin "K33")
    (pin "K34")
    (pin "K35")
    (pin "K36")
    (pin "K37")
    (pin "K38")
    (pin "K39")
    (pin "K4")
    (pin "K40")
    (pin "K5")
    (pin "K6")
    (pin "K7")
    (pin "K8")
    (pin "K9")
    (pin "G1")
    (pin "G10")
    (pin "G11")
    (pin "G12")
    (pin "G13")
    (pin "G14")
    (pin "G15")
    (pin "G16")
    (pin "G17")
    (pin "G18")
    (pin "G19")
    (pin "G2")
    (pin "G20")
    (pin "G21")
    (pin "G22")
    (pin "G23")
    (pin "G24")
    (pin "G25")
    (pin "G26")
    (pin "G27")
    (pin "G28")
    (pin "G29")
    (pin "G3")
    (pin "G30")
    (pin "G31")
    (pin "G32")
    (pin "G33")
    (pin "G34")
    (pin "G35")
    (pin "G36")
    (pin "G37")
    (pin "G38")
    (pin "G39")
    (pin "G4")
    (pin "G40")
    (pin "G5")
    (pin "G6")
    (pin "G7")
    (pin "G8")
    (pin "G9")
    (pin "H1")
    (pin "H10")
    (pin "H11")
    (pin "H12")
    (pin "H13")
    (pin "H14")
    (pin "H15")
    (pin "H16")
    (pin "H17")
    (pin "H18")
    (pin "H19")
    (pin "H2")
    (pin "H20")
    (pin "H21")
    (pin "H22")
    (pin "H23")
    (pin "H24")
    (pin "H25")
    (pin "H26")
    (pin "H27")
    (pin "H28")
    (pin "H29")
    (pin "H3")
    (pin "H30")
    (pin "H31")
    (pin "H32")
    (pin "H33")
    (pin "H34")
    (pin "H35")
    (pin "H36")
    (pin "H37")
    (pin "H38")
    (pin "H39")
    (pin "H4")
    (pin "H40")
    (pin "H5")
    (pin "H6")
    (pin "H7")
    (pin "H8")
    (pin "H9")
    (pin "E1")
    (pin "E10")
    (pin "E11")
    (pin "E12")
    (pin "E13")
    (pin "E14")
    (pin "E15")
    (pin "E16")
    (pin "E17")
    (pin "E18")
    (pin "E19")
    (pin "E2")
    (pin "E20")
    (pin "E21")
    (pin "E22")
    (pin "E23")
    (pin "E24")
    (pin "E25")
    (pin "E26")
    (pin "E27")
    (pin "E28")
    (pin "E29")
    (pin "E3")
    (pin "E30")
    (pin "E31")
    (pin "E32")
    (pin "E33")
    (pin "E34")
    (pin "E35")
    (pin "E36")
    (pin "E37")
    (pin "E38")
    (pin "E39")
    (pin "E4")
    (pin "E40")
    (pin "E5")
    (pin "E6")
    (pin "E7")
    (pin "E8")
    (pin "E9")
    (pin "F1")
    (pin "F10")
    (pin "F11")
    (pin "F12")
    (pin "F13")
    (pin "F14")
    (pin "F15")
    (pin "F16")
    (pin "F17")
    (pin "F18")
    (pin "F19")
    (pin "F2")
    (pin "F20")
    (pin "F21")
    (pin "F22")
    (pin "F23")
    (pin "F24")
    (pin "F25")
    (pin "F26")
    (pin "F27")
    (pin "F28")
    (pin "F29")
    (pin "F3")
    (pin "F30")
    (pin "F31")
    (pin "F32")
    (pin "F33")
    (pin "F34")
    (pin "F35")
    (pin "F36")
    (pin "F37")
    (pin "F38")
    (pin "F39")
    (pin "F4")
    (pin "F40")
    (pin "F5")
    (pin "F6")
    (pin "F7")
    (pin "F8")
    (pin "F9")
    (pin "C1")
    (pin "C10")
    (pin "C11")
    (pin "C12")
    (pin "C13")
    (pin "C14")
    (pin "C15")
    (pin "C16")
    (pin "C17")
    (pin "C18")
    (pin "C19")
    (pin "C2")
    (pin "C20")
    (pin "C21")
    (pin "C22")
    (pin "C23")
    (pin "C24")
    (pin "C25")
    (pin "C26")
    (pin "C27")
    (pin "C28")
    (pin "C29")
    (pin "C3")
    (pin "C30")
    (pin "C31")
    (pin "C32")
    (pin "C33")
    (pin "C34")
    (pin "C35")
    (pin "C36")
    (pin "C37")
    (pin "C38")
    (pin "C39")
    (pin "C4")
    (pin "C40")
    (pin "C5")
    (pin "C6")
    (pin "C7")
    (pin "C8")
    (pin "C9")
    (pin "D1")
    (pin "D10")
    (pin "D11")
    (pin "D12")
    (pin "D13")
    (pin "D14")
    (pin "D15")
    (pin "D16")
    (pin "D17")
    (pin "D18")
    (pin "D19")
    (pin "D2")
    (pin "D20")
    (pin "D21")
    (pin "D22")
    (pin "D23")
    (pin "D24")
    (pin "D25")
    (pin "D26")
    (pin "D27")
    (pin "D28")
    (pin "D29")
    (pin "D3")
    (pin "D30")
    (pin "D31")
    (pin "D32")
    (pin "D33")
    (pin "D34")
    (pin "D35")
    (pin "D36")
    (pin "D37")
    (pin "D38")
    (pin "D39")
    (pin "D4")
    (pin "D40")
    (pin "D5")
    (pin "D6")
    (pin "D7")
    (pin "D8")
    (pin "D9")
    (pin "A1")
    (pin "A10")
    (pin "A11")
    (pin "A12")
    (pin "A13")
    (pin "A14")
    (pin "A15")
    (pin "A16")
    (pin "A17")
    (pin "A18")
    (pin "A19")
    (pin "A2")
    (pin "A20")
    (pin "A21")
    (pin "A22")
    (pin "A23")
    (pin "A24")
    (pin "A25")
    (pin "A26")
    (pin "A27")
    (pin "A28")
    (pin "A29")
    (pin "A3")
    (pin "A30")
    (pin "A31")
    (pin "A32")
    (pin "A33")
    (pin "A34")
    (pin "A35")
    (pin "A36")
    (pin "A37")
    (pin "A38")
    (pin "A39")
    (pin "A4")
    (pin "A40")
    (pin "A5")
    (pin "A6")
    (pin "A7")
    (pin "A8")
    (pin "A9")
    (pin "B1")
    (pin "B10")
    (pin "B11")
    (pin "B12")
    (pin "B13")
    (pin "B14")
    (pin "B15")
    (pin "B16")
    (pin "B17")
    (pin "B18")
    (pin "B19")
    (pin "B2")
    (pin "B20")
    (pin "B21")
    (pin "B22")
    (pin "B23")
    (pin "B24")
    (pin "B25")
    (pin "B26")
    (pin "B27")
    (pin "B28")
    (pin "B29")
    (pin "B3")
    (pin "B30")
    (pin "B31")
    (pin "B32")
    (pin "B33")
    (pin "B34")
    (pin "B35")
    (pin "B36")
    (pin "B37")
    (pin "B38")
    (pin "B39")
    (pin "B4")
    (pin "B40")
    (pin "B5")
    (pin "B6")
    (pin "B7")
    (pin "B8")
    (pin "B9")
    (instances
      (project "data-center-rdimm-ddr4-tester"
        (path ""
          (reference "J5") (unit 2)
        )
      )
    )
  )

  (symbol (lib_id "antmicropower:GND") (at 154.94 125.73 0) (unit 1)
    (in_bom yes) (on_board yes) (dnp no) (fields_autoplaced)
    (property "Reference" "#PWR0406" (at 154.94 132.08 0)
      (effects (font (size 1.27 1.27)) hide)
    )
    (property "Value" "GND" (at 154.94 129.54 0)
      (effects (font (size 1.27 1.27)))
    )
    (property "Footprint" "" (at 154.94 125.73 0)
      (effects (font (size 1.27 1.27)) hide)
    )
    (property "Datasheet" "" (at 154.94 125.73 0)
      (effects (font (size 1.27 1.27)) hide)
    )
    (property "Author" "Antmicro" (at 163.83 133.35 0)
      (effects (font (size 1.27 1.27) (thickness 0.15)) (justify left bottom) hide)
    )
    (property "License" "Apache-2.0" (at 163.83 135.89 0)
      (effects (font (size 1.27 1.27) (thickness 0.15)) (justify left bottom) hide)
    )
    (pin "1")
    (instances
      (project "data-center-rdimm-ddr4-tester"
        (path ""
          (reference "#PWR0406") (unit 1)
        )
      )
    )
  )

  (symbol (lib_id "antmicroFMCConnectors:ASP-134486-01") (at 240.665 39.37 0) (unit 5)
    (in_bom yes) (on_board yes) (dnp no) (fields_autoplaced)
    (property "Reference" "J5" (at 255.905 31.115 0)
      (effects (font (size 1.27 1.27)))
    )
    (property "Value" "ASP-134486-01" (at 255.905 33.655 0)
      (effects (font (size 1.27 1.27) (thickness 0.15)))
    )
    (property "Footprint" "antmicro-footprints:FMC_SAMTEC_ASP-134486-01" (at 286.385 50.8 0)
      (effects (font (size 1.27 1.27) (thickness 0.15)) (justify left bottom) hide)
    )
    (property "Datasheet" "https://suddendocs.samtec.com/prints/asp-134486-01-mkt.pdf?_gl=1*a2d3qa*_ga*MzYxMTM5My4xNjYzOTI3MDkz*_ga_3KFNZC07WW*MTY2NDIwMTUxMC4zLjAuMTY2NDIwMTUxMC42MC4wLjA." (at 286.385 53.34 0)
      (effects (font (size 1.27 1.27) (thickness 0.15)) (justify left bottom) hide)
    )
    (property "Manufacturer" "Samtec" (at 286.385 55.88 0)
      (effects (font (size 1.27 1.27) (thickness 0.15)) (justify left bottom) hide)
    )
    (property "MPN" "ASP-134486-01" (at 286.385 58.42 0)
      (effects (font (size 1.27 1.27) (thickness 0.15)) (justify left bottom) hide)
    )
    (property "Author" "Antmicro" (at 286.385 60.96 0)
      (effects (font (size 1.27 1.27) (thickness 0.15)) (justify left bottom) hide)
    )
    (property "License" "Apache-2.0" (at 286.385 63.5 0)
      (effects (font (size 1.27 1.27) (thickness 0.15)) (justify left bottom) hide)
    )
    (pin "J1")
    (pin "J10")
    (pin "J11")
    (pin "J12")
    (pin "J13")
    (pin "J14")
    (pin "J15")
    (pin "J16")
    (pin "J17")
    (pin "J18")
    (pin "J19")
    (pin "J2")
    (pin "J20")
    (pin "J21")
    (pin "J22")
    (pin "J23")
    (pin "J24")
    (pin "J25")
    (pin "J26")
    (pin "J27")
    (pin "J28")
    (pin "J29")
    (pin "J3")
    (pin "J30")
    (pin "J31")
    (pin "J32")
    (pin "J33")
    (pin "J34")
    (pin "J35")
    (pin "J36")
    (pin "J37")
    (pin "J38")
    (pin "J39")
    (pin "J4")
    (pin "J40")
    (pin "J5")
    (pin "J6")
    (pin "J7")
    (pin "J8")
    (pin "J9")
    (pin "K1")
    (pin "K10")
    (pin "K11")
    (pin "K12")
    (pin "K13")
    (pin "K14")
    (pin "K15")
    (pin "K16")
    (pin "K17")
    (pin "K18")
    (pin "K19")
    (pin "K2")
    (pin "K20")
    (pin "K21")
    (pin "K22")
    (pin "K23")
    (pin "K24")
    (pin "K25")
    (pin "K26")
    (pin "K27")
    (pin "K28")
    (pin "K29")
    (pin "K3")
    (pin "K30")
    (pin "K31")
    (pin "K32")
    (pin "K33")
    (pin "K34")
    (pin "K35")
    (pin "K36")
    (pin "K37")
    (pin "K38")
    (pin "K39")
    (pin "K4")
    (pin "K40")
    (pin "K5")
    (pin "K6")
    (pin "K7")
    (pin "K8")
    (pin "K9")
    (pin "G1")
    (pin "G10")
    (pin "G11")
    (pin "G12")
    (pin "G13")
    (pin "G14")
    (pin "G15")
    (pin "G16")
    (pin "G17")
    (pin "G18")
    (pin "G19")
    (pin "G2")
    (pin "G20")
    (pin "G21")
    (pin "G22")
    (pin "G23")
    (pin "G24")
    (pin "G25")
    (pin "G26")
    (pin "G27")
    (pin "G28")
    (pin "G29")
    (pin "G3")
    (pin "G30")
    (pin "G31")
    (pin "G32")
    (pin "G33")
    (pin "G34")
    (pin "G35")
    (pin "G36")
    (pin "G37")
    (pin "G38")
    (pin "G39")
    (pin "G4")
    (pin "G40")
    (pin "G5")
    (pin "G6")
    (pin "G7")
    (pin "G8")
    (pin "G9")
    (pin "H1")
    (pin "H10")
    (pin "H11")
    (pin "H12")
    (pin "H13")
    (pin "H14")
    (pin "H15")
    (pin "H16")
    (pin "H17")
    (pin "H18")
    (pin "H19")
    (pin "H2")
    (pin "H20")
    (pin "H21")
    (pin "H22")
    (pin "H23")
    (pin "H24")
    (pin "H25")
    (pin "H26")
    (pin "H27")
    (pin "H28")
    (pin "H29")
    (pin "H3")
    (pin "H30")
    (pin "H31")
    (pin "H32")
    (pin "H33")
    (pin "H34")
    (pin "H35")
    (pin "H36")
    (pin "H37")
    (pin "H38")
    (pin "H39")
    (pin "H4")
    (pin "H40")
    (pin "H5")
    (pin "H6")
    (pin "H7")
    (pin "H8")
    (pin "H9")
    (pin "E1")
    (pin "E10")
    (pin "E11")
    (pin "E12")
    (pin "E13")
    (pin "E14")
    (pin "E15")
    (pin "E16")
    (pin "E17")
    (pin "E18")
    (pin "E19")
    (pin "E2")
    (pin "E20")
    (pin "E21")
    (pin "E22")
    (pin "E23")
    (pin "E24")
    (pin "E25")
    (pin "E26")
    (pin "E27")
    (pin "E28")
    (pin "E29")
    (pin "E3")
    (pin "E30")
    (pin "E31")
    (pin "E32")
    (pin "E33")
    (pin "E34")
    (pin "E35")
    (pin "E36")
    (pin "E37")
    (pin "E38")
    (pin "E39")
    (pin "E4")
    (pin "E40")
    (pin "E5")
    (pin "E6")
    (pin "E7")
    (pin "E8")
    (pin "E9")
    (pin "F1")
    (pin "F10")
    (pin "F11")
    (pin "F12")
    (pin "F13")
    (pin "F14")
    (pin "F15")
    (pin "F16")
    (pin "F17")
    (pin "F18")
    (pin "F19")
    (pin "F2")
    (pin "F20")
    (pin "F21")
    (pin "F22")
    (pin "F23")
    (pin "F24")
    (pin "F25")
    (pin "F26")
    (pin "F27")
    (pin "F28")
    (pin "F29")
    (pin "F3")
    (pin "F30")
    (pin "F31")
    (pin "F32")
    (pin "F33")
    (pin "F34")
    (pin "F35")
    (pin "F36")
    (pin "F37")
    (pin "F38")
    (pin "F39")
    (pin "F4")
    (pin "F40")
    (pin "F5")
    (pin "F6")
    (pin "F7")
    (pin "F8")
    (pin "F9")
    (pin "C1")
    (pin "C10")
    (pin "C11")
    (pin "C12")
    (pin "C13")
    (pin "C14")
    (pin "C15")
    (pin "C16")
    (pin "C17")
    (pin "C18")
    (pin "C19")
    (pin "C2")
    (pin "C20")
    (pin "C21")
    (pin "C22")
    (pin "C23")
    (pin "C24")
    (pin "C25")
    (pin "C26")
    (pin "C27")
    (pin "C28")
    (pin "C29")
    (pin "C3")
    (pin "C30")
    (pin "C31")
    (pin "C32")
    (pin "C33")
    (pin "C34")
    (pin "C35")
    (pin "C36")
    (pin "C37")
    (pin "C38")
    (pin "C39")
    (pin "C4")
    (pin "C40")
    (pin "C5")
    (pin "C6")
    (pin "C7")
    (pin "C8")
    (pin "C9")
    (pin "D1")
    (pin "D10")
    (pin "D11")
    (pin "D12")
    (pin "D13")
    (pin "D14")
    (pin "D15")
    (pin "D16")
    (pin "D17")
    (pin "D18")
    (pin "D19")
    (pin "D2")
    (pin "D20")
    (pin "D21")
    (pin "D22")
    (pin "D23")
    (pin "D24")
    (pin "D25")
    (pin "D26")
    (pin "D27")
    (pin "D28")
    (pin "D29")
    (pin "D3")
    (pin "D30")
    (pin "D31")
    (pin "D32")
    (pin "D33")
    (pin "D34")
    (pin "D35")
    (pin "D36")
    (pin "D37")
    (pin "D38")
    (pin "D39")
    (pin "D4")
    (pin "D40")
    (pin "D5")
    (pin "D6")
    (pin "D7")
    (pin "D8")
    (pin "D9")
    (pin "A1")
    (pin "A10")
    (pin "A11")
    (pin "A12")
    (pin "A13")
    (pin "A14")
    (pin "A15")
    (pin "A16")
    (pin "A17")
    (pin "A18")
    (pin "A19")
    (pin "A2")
    (pin "A20")
    (pin "A21")
    (pin "A22")
    (pin "A23")
    (pin "A24")
    (pin "A25")
    (pin "A26")
    (pin "A27")
    (pin "A28")
    (pin "A29")
    (pin "A3")
    (pin "A30")
    (pin "A31")
    (pin "A32")
    (pin "A33")
    (pin "A34")
    (pin "A35")
    (pin "A36")
    (pin "A37")
    (pin "A38")
    (pin "A39")
    (pin "A4")
    (pin "A40")
    (pin "A5")
    (pin "A6")
    (pin "A7")
    (pin "A8")
    (pin "A9")
    (pin "B1")
    (pin "B10")
    (pin "B11")
    (pin "B12")
    (pin "B13")
    (pin "B14")
    (pin "B15")
    (pin "B16")
    (pin "B17")
    (pin "B18")
    (pin "B19")
    (pin "B2")
    (pin "B20")
    (pin "B21")
    (pin "B22")
    (pin "B23")
    (pin "B24")
    (pin "B25")
    (pin "B26")
    (pin "B27")
    (pin "B28")
    (pin "B29")
    (pin "B3")
    (pin "B30")
    (pin "B31")
    (pin "B32")
    (pin "B33")
    (pin "B34")
    (pin "B35")
    (pin "B36")
    (pin "B37")
    (pin "B38")
    (pin "B39")
    (pin "B4")
    (pin "B40")
    (pin "B5")
    (pin "B6")
    (pin "B7")
    (pin "B8")
    (pin "B9")
    (instances
      (project "data-center-rdimm-ddr4-tester"
        (path ""
          (reference "J5") (unit 5)
        )
      )
    )
  )

  (symbol (lib_id "antmicropower:GND") (at 62.23 254.635 0) (unit 1)
    (in_bom yes) (on_board yes) (dnp no) (fields_autoplaced)
    (property "Reference" "#PWR0350" (at 62.23 260.985 0)
      (effects (font (size 1.27 1.27)) hide)
    )
    (property "Value" "GND" (at 62.23 258.445 0)
      (effects (font (size 1.27 1.27)))
    )
    (property "Footprint" "" (at 62.23 254.635 0)
      (effects (font (size 1.27 1.27)) hide)
    )
    (property "Datasheet" "" (at 62.23 254.635 0)
      (effects (font (size 1.27 1.27)) hide)
    )
    (property "Author" "Antmicro" (at 71.12 262.255 0)
      (effects (font (size 1.27 1.27) (thickness 0.15)) (justify left bottom) hide)
    )
    (property "License" "Apache-2.0" (at 71.12 264.795 0)
      (effects (font (size 1.27 1.27) (thickness 0.15)) (justify left bottom) hide)
    )
    (pin "1")
    (instances
      (project "data-center-rdimm-ddr4-tester"
        (path ""
          (reference "#PWR0350") (unit 1)
        )
      )
    )
  )

  (symbol (lib_id "antmicropower:GND") (at 231.14 251.46 0) (unit 1)
    (in_bom yes) (on_board yes) (dnp no) (fields_autoplaced)
    (property "Reference" "#PWR0345" (at 231.14 257.81 0)
      (effects (font (size 1.27 1.27)) hide)
    )
    (property "Value" "GND" (at 231.14 255.27 0)
      (effects (font (size 1.27 1.27)))
    )
    (property "Footprint" "" (at 231.14 251.46 0)
      (effects (font (size 1.27 1.27)) hide)
    )
    (property "Datasheet" "" (at 231.14 251.46 0)
      (effects (font (size 1.27 1.27)) hide)
    )
    (property "Author" "Antmicro" (at 240.03 259.08 0)
      (effects (font (size 1.27 1.27) (thickness 0.15)) (justify left bottom) hide)
    )
    (property "License" "Apache-2.0" (at 240.03 261.62 0)
      (effects (font (size 1.27 1.27) (thickness 0.15)) (justify left bottom) hide)
    )
    (pin "1")
    (instances
      (project "data-center-rdimm-ddr4-tester"
        (path ""
          (reference "#PWR0345") (unit 1)
        )
      )
    )
  )

  (symbol (lib_id "antmicroCapacitors0402:C_100n_0402") (at 349.25 146.685 0) (unit 1)
    (in_bom yes) (on_board yes) (dnp no)
    (property "Reference" "C270" (at 347.98 145.415 0)
      (effects (font (size 1.524 1.524)))
    )
    (property "Value" "C_100n_0402" (at 369.57 156.845 0)
      (effects (font (size 1.27 1.27) (thickness 0.15)) (justify left bottom) hide)
    )
    (property "Footprint" "antmicro-footprints:C_0402_1005Metric" (at 369.57 159.385 0)
      (effects (font (size 1.27 1.27) (thickness 0.15)) (justify left bottom) hide)
    )
    (property "Datasheet" "https://search.murata.co.jp/Ceramy/image/img/A01X/G101/ENG/GRM155R61H104KE14-01.pdf" (at 369.57 161.925 0)
      (effects (font (size 1.27 1.27) (thickness 0.15)) (justify left bottom) hide)
    )
    (property "Manufacturer" "Murata" (at 369.57 167.005 0)
      (effects (font (size 1.27 1.27) (thickness 0.15)) (justify left bottom) hide)
    )
    (property "MPN" "GRM155R61H104KE14D" (at 369.57 164.465 0)
      (effects (font (size 1.27 1.27) (thickness 0.15)) (justify left bottom) hide)
    )
    (property "Val" "100n" (at 354.965 145.415 0)
      (effects (font (size 1.27 1.27) (thickness 0.15)))
    )
    (property "License" "Apache-2.0" (at 369.57 169.545 0)
      (effects (font (size 1.27 1.27) (thickness 0.15)) (justify left bottom) hide)
    )
    (property "Author" "Antmicro" (at 369.57 172.085 0)
      (effects (font (size 1.27 1.27) (thickness 0.15)) (justify left bottom) hide)
    )
    (property "Voltage" "50V" (at 369.57 174.625 0)
      (effects (font (size 1.27 1.27)) (justify left bottom) hide)
    )
    (property "Dielectric" "X5R" (at 369.57 177.165 0)
      (effects (font (size 1.27 1.27)) (justify left bottom) hide)
    )
    (pin "1")
    (pin "2")
    (instances
      (project "data-center-rdimm-ddr4-tester"
        (path ""
          (reference "C270") (unit 1)
        )
      )
    )
  )

  (symbol (lib_id "antmicroCapacitors0402:C_100n_0402") (at 354.33 156.845 180) (unit 1)
    (in_bom yes) (on_board yes) (dnp no)
    (property "Reference" "C272" (at 347.98 155.575 0)
      (effects (font (size 1.524 1.524)))
    )
    (property "Value" "C_100n_0402" (at 334.01 146.685 0)
      (effects (font (size 1.27 1.27) (thickness 0.15)) (justify left bottom) hide)
    )
    (property "Footprint" "antmicro-footprints:C_0402_1005Metric" (at 334.01 144.145 0)
      (effects (font (size 1.27 1.27) (thickness 0.15)) (justify left bottom) hide)
    )
    (property "Datasheet" "https://search.murata.co.jp/Ceramy/image/img/A01X/G101/ENG/GRM155R61H104KE14-01.pdf" (at 334.01 141.605 0)
      (effects (font (size 1.27 1.27) (thickness 0.15)) (justify left bottom) hide)
    )
    (property "Manufacturer" "Murata" (at 334.01 136.525 0)
      (effects (font (size 1.27 1.27) (thickness 0.15)) (justify left bottom) hide)
    )
    (property "MPN" "GRM155R61H104KE14D" (at 334.01 139.065 0)
      (effects (font (size 1.27 1.27) (thickness 0.15)) (justify left bottom) hide)
    )
    (property "Val" "100n" (at 354.965 155.575 0)
      (effects (font (size 1.27 1.27) (thickness 0.15)))
    )
    (property "License" "Apache-2.0" (at 334.01 133.985 0)
      (effects (font (size 1.27 1.27) (thickness 0.15)) (justify left bottom) hide)
    )
    (property "Author" "Antmicro" (at 334.01 131.445 0)
      (effects (font (size 1.27 1.27) (thickness 0.15)) (justify left bottom) hide)
    )
    (property "Voltage" "50V" (at 334.01 128.905 0)
      (effects (font (size 1.27 1.27)) (justify left bottom) hide)
    )
    (property "Dielectric" "X5R" (at 334.01 126.365 0)
      (effects (font (size 1.27 1.27)) (justify left bottom) hide)
    )
    (pin "1")
    (pin "2")
    (instances
      (project "data-center-rdimm-ddr4-tester"
        (path ""
          (reference "C272") (unit 1)
        )
      )
    )
  )

  (symbol (lib_id "antmicroCapacitors0402:C_100n_0402") (at 337.82 144.145 0) (unit 1)
    (in_bom yes) (on_board yes) (dnp no)
    (property "Reference" "C269" (at 336.55 142.875 0)
      (effects (font (size 1.524 1.524)))
    )
    (property "Value" "C_100n_0402" (at 358.14 154.305 0)
      (effects (font (size 1.27 1.27) (thickness 0.15)) (justify left bottom) hide)
    )
    (property "Footprint" "antmicro-footprints:C_0402_1005Metric" (at 358.14 156.845 0)
      (effects (font (size 1.27 1.27) (thickness 0.15)) (justify left bottom) hide)
    )
    (property "Datasheet" "https://search.murata.co.jp/Ceramy/image/img/A01X/G101/ENG/GRM155R61H104KE14-01.pdf" (at 358.14 159.385 0)
      (effects (font (size 1.27 1.27) (thickness 0.15)) (justify left bottom) hide)
    )
    (property "Manufacturer" "Murata" (at 358.14 164.465 0)
      (effects (font (size 1.27 1.27) (thickness 0.15)) (justify left bottom) hide)
    )
    (property "MPN" "GRM155R61H104KE14D" (at 358.14 161.925 0)
      (effects (font (size 1.27 1.27) (thickness 0.15)) (justify left bottom) hide)
    )
    (property "Val" "100n" (at 343.535 142.875 0)
      (effects (font (size 1.27 1.27) (thickness 0.15)))
    )
    (property "License" "Apache-2.0" (at 358.14 167.005 0)
      (effects (font (size 1.27 1.27) (thickness 0.15)) (justify left bottom) hide)
    )
    (property "Author" "Antmicro" (at 358.14 169.545 0)
      (effects (font (size 1.27 1.27) (thickness 0.15)) (justify left bottom) hide)
    )
    (property "Voltage" "50V" (at 358.14 172.085 0)
      (effects (font (size 1.27 1.27)) (justify left bottom) hide)
    )
    (property "Dielectric" "X5R" (at 358.14 174.625 0)
      (effects (font (size 1.27 1.27)) (justify left bottom) hide)
    )
    (pin "1")
    (pin "2")
    (instances
      (project "data-center-rdimm-ddr4-tester"
        (path ""
          (reference "C269") (unit 1)
        )
      )
    )
  )

  (symbol (lib_id "antmicroResistors0402:R_33R_0402") (at 344.17 66.675 0) (unit 1)
    (in_bom yes) (on_board yes) (dnp no)
    (property "Reference" "R151" (at 341.63 65.405 0)
      (effects (font (size 1.524 1.524)))
    )
    (property "Value" "R_33R_0402" (at 364.49 79.375 0)
      (effects (font (size 1.27 1.27) (thickness 0.15)) (justify left bottom) hide)
    )
    (property "Footprint" "antmicro-footprints:R_0402_1005Metric" (at 364.49 81.915 0)
      (effects (font (size 1.27 1.27) (thickness 0.15)) (justify left bottom) hide)
    )
    (property "Datasheet" "https://www.bourns.com/docs/product-datasheets/cr.pdf" (at 364.49 84.455 0)
      (effects (font (size 1.27 1.27) (thickness 0.15)) (justify left bottom) hide)
    )
    (property "Manufacturer" "Bourns" (at 364.49 89.535 0)
      (effects (font (size 1.27 1.27) (thickness 0.15)) (justify left bottom) hide)
    )
    (property "MPN" "CR0402-FX-33R0GLF" (at 364.49 86.995 0)
      (effects (font (size 1.27 1.27) (thickness 0.15)) (justify left bottom) hide)
    )
    (property "Val" "33R" (at 351.155 65.405 0)
      (effects (font (size 1.27 1.27) (thickness 0.15)))
    )
    (property "License" "Apache-2.0" (at 364.49 92.075 0)
      (effects (font (size 1.27 1.27) (thickness 0.15)) (justify left bottom) hide)
    )
    (property "Author" "Antmicro" (at 364.49 94.615 0)
      (effects (font (size 1.27 1.27) (thickness 0.15)) (justify left bottom) hide)
    )
    (property "Tolerance" "1%" (at 364.49 76.835 0)
      (effects (font (size 1.27 1.27)) (justify left bottom) hide)
    )
    (pin "1")
    (pin "2")
    (instances
      (project "data-center-rdimm-ddr4-tester"
        (path ""
          (reference "R151") (unit 1)
        )
      )
    )
  )

  (symbol (lib_id "antmicroCapacitors0402:C_100n_0402") (at 349.25 167.005 0) (unit 1)
    (in_bom yes) (on_board yes) (dnp no)
    (property "Reference" "C274" (at 347.98 165.735 0)
      (effects (font (size 1.524 1.524)))
    )
    (property "Value" "C_100n_0402" (at 369.57 177.165 0)
      (effects (font (size 1.27 1.27) (thickness 0.15)) (justify left bottom) hide)
    )
    (property "Footprint" "antmicro-footprints:C_0402_1005Metric" (at 369.57 179.705 0)
      (effects (font (size 1.27 1.27) (thickness 0.15)) (justify left bottom) hide)
    )
    (property "Datasheet" "https://search.murata.co.jp/Ceramy/image/img/A01X/G101/ENG/GRM155R61H104KE14-01.pdf" (at 369.57 182.245 0)
      (effects (font (size 1.27 1.27) (thickness 0.15)) (justify left bottom) hide)
    )
    (property "Manufacturer" "Murata" (at 369.57 187.325 0)
      (effects (font (size 1.27 1.27) (thickness 0.15)) (justify left bottom) hide)
    )
    (property "MPN" "GRM155R61H104KE14D" (at 369.57 184.785 0)
      (effects (font (size 1.27 1.27) (thickness 0.15)) (justify left bottom) hide)
    )
    (property "Val" "100n" (at 354.965 165.735 0)
      (effects (font (size 1.27 1.27) (thickness 0.15)))
    )
    (property "License" "Apache-2.0" (at 369.57 189.865 0)
      (effects (font (size 1.27 1.27) (thickness 0.15)) (justify left bottom) hide)
    )
    (property "Author" "Antmicro" (at 369.57 192.405 0)
      (effects (font (size 1.27 1.27) (thickness 0.15)) (justify left bottom) hide)
    )
    (property "Voltage" "50V" (at 369.57 194.945 0)
      (effects (font (size 1.27 1.27)) (justify left bottom) hide)
    )
    (property "Dielectric" "X5R" (at 369.57 197.485 0)
      (effects (font (size 1.27 1.27)) (justify left bottom) hide)
    )
    (pin "1")
    (pin "2")
    (instances
      (project "data-center-rdimm-ddr4-tester"
        (path ""
          (reference "C274") (unit 1)
        )
      )
    )
  )

  (symbol (lib_id "antmicroResistors0402:R_4k7_0402") (at 200.66 219.71 90) (mirror x) (unit 1)
    (in_bom yes) (on_board yes) (dnp no) (fields_autoplaced)
    (property "Reference" "R155" (at 198.12 220.98 90)
      (effects (font (size 1.524 1.524)) (justify left))
    )
    (property "Value" "R_4k7_0402" (at 213.36 240.03 0)
      (effects (font (size 1.27 1.27) (thickness 0.15)) (justify left bottom) hide)
    )
    (property "Footprint" "antmicro-footprints:R_0402_1005Metric" (at 215.9 240.03 0)
      (effects (font (size 1.27 1.27) (thickness 0.15)) (justify left bottom) hide)
    )
    (property "Datasheet" "https://www.bourns.com/docs/product-datasheets/cr.pdf" (at 218.44 240.03 0)
      (effects (font (size 1.27 1.27) (thickness 0.15)) (justify left bottom) hide)
    )
    (property "Manufacturer" "Bourns" (at 223.52 240.03 0)
      (effects (font (size 1.27 1.27) (thickness 0.15)) (justify left bottom) hide)
    )
    (property "MPN" "CR0402-FX-4701GLF" (at 220.98 240.03 0)
      (effects (font (size 1.27 1.27) (thickness 0.15)) (justify left bottom) hide)
    )
    (property "Val" "4k7" (at 198.12 224.1549 90)
      (effects (font (size 1.27 1.27) (thickness 0.15)) (justify left))
    )
    (property "License" "Apache-2.0" (at 226.06 240.03 0)
      (effects (font (size 1.27 1.27) (thickness 0.15)) (justify left bottom) hide)
    )
    (property "Author" "Antmicro" (at 228.6 240.03 0)
      (effects (font (size 1.27 1.27) (thickness 0.15)) (justify left bottom) hide)
    )
    (property "Tolerance" "1%" (at 210.82 240.03 0)
      (effects (font (size 1.27 1.27)) (justify left bottom) hide)
    )
    (pin "1")
    (pin "2")
    (instances
      (project "data-center-rdimm-ddr4-tester"
        (path ""
          (reference "R155") (unit 1)
        )
      )
    )
  )

  (symbol (lib_id "antmicroCapacitors0402:C_100n_0402") (at 337.82 123.825 0) (unit 1)
    (in_bom yes) (on_board yes) (dnp no)
    (property "Reference" "C265" (at 336.55 122.555 0)
      (effects (font (size 1.524 1.524)))
    )
    (property "Value" "C_100n_0402" (at 358.14 133.985 0)
      (effects (font (size 1.27 1.27) (thickness 0.15)) (justify left bottom) hide)
    )
    (property "Footprint" "antmicro-footprints:C_0402_1005Metric" (at 358.14 136.525 0)
      (effects (font (size 1.27 1.27) (thickness 0.15)) (justify left bottom) hide)
    )
    (property "Datasheet" "https://search.murata.co.jp/Ceramy/image/img/A01X/G101/ENG/GRM155R61H104KE14-01.pdf" (at 358.14 139.065 0)
      (effects (font (size 1.27 1.27) (thickness 0.15)) (justify left bottom) hide)
    )
    (property "Manufacturer" "Murata" (at 358.14 144.145 0)
      (effects (font (size 1.27 1.27) (thickness 0.15)) (justify left bottom) hide)
    )
    (property "MPN" "GRM155R61H104KE14D" (at 358.14 141.605 0)
      (effects (font (size 1.27 1.27) (thickness 0.15)) (justify left bottom) hide)
    )
    (property "Val" "100n" (at 343.535 122.555 0)
      (effects (font (size 1.27 1.27) (thickness 0.15)))
    )
    (property "License" "Apache-2.0" (at 358.14 146.685 0)
      (effects (font (size 1.27 1.27) (thickness 0.15)) (justify left bottom) hide)
    )
    (property "Author" "Antmicro" (at 358.14 149.225 0)
      (effects (font (size 1.27 1.27) (thickness 0.15)) (justify left bottom) hide)
    )
    (property "Voltage" "50V" (at 358.14 151.765 0)
      (effects (font (size 1.27 1.27)) (justify left bottom) hide)
    )
    (property "Dielectric" "X5R" (at 358.14 154.305 0)
      (effects (font (size 1.27 1.27)) (justify left bottom) hide)
    )
    (pin "1")
    (pin "2")
    (instances
      (project "data-center-rdimm-ddr4-tester"
        (path ""
          (reference "C265") (unit 1)
        )
      )
    )
  )

  (symbol (lib_id "antmicroResistors0402:R_33R_0402") (at 344.17 53.975 0) (unit 1)
    (in_bom yes) (on_board yes) (dnp no)
    (property "Reference" "R148" (at 341.63 52.705 0)
      (effects (font (size 1.524 1.524)))
    )
    (property "Value" "R_33R_0402" (at 364.49 66.675 0)
      (effects (font (size 1.27 1.27) (thickness 0.15)) (justify left bottom) hide)
    )
    (property "Footprint" "antmicro-footprints:R_0402_1005Metric" (at 364.49 69.215 0)
      (effects (font (size 1.27 1.27) (thickness 0.15)) (justify left bottom) hide)
    )
    (property "Datasheet" "https://www.bourns.com/docs/product-datasheets/cr.pdf" (at 364.49 71.755 0)
      (effects (font (size 1.27 1.27) (thickness 0.15)) (justify left bottom) hide)
    )
    (property "Manufacturer" "Bourns" (at 364.49 76.835 0)
      (effects (font (size 1.27 1.27) (thickness 0.15)) (justify left bottom) hide)
    )
    (property "MPN" "CR0402-FX-33R0GLF" (at 364.49 74.295 0)
      (effects (font (size 1.27 1.27) (thickness 0.15)) (justify left bottom) hide)
    )
    (property "Val" "33R" (at 351.155 52.705 0)
      (effects (font (size 1.27 1.27) (thickness 0.15)))
    )
    (property "License" "Apache-2.0" (at 364.49 79.375 0)
      (effects (font (size 1.27 1.27) (thickness 0.15)) (justify left bottom) hide)
    )
    (property "Author" "Antmicro" (at 364.49 81.915 0)
      (effects (font (size 1.27 1.27) (thickness 0.15)) (justify left bottom) hide)
    )
    (property "Tolerance" "1%" (at 364.49 64.135 0)
      (effects (font (size 1.27 1.27)) (justify left bottom) hide)
    )
    (pin "1")
    (pin "2")
    (instances
      (project "data-center-rdimm-ddr4-tester"
        (path ""
          (reference "R148") (unit 1)
        )
      )
    )
  )

  (symbol (lib_id "antmicropower:GND") (at 154.94 253.365 0) (unit 1)
    (in_bom yes) (on_board yes) (dnp no) (fields_autoplaced)
    (property "Reference" "#PWR0346" (at 154.94 259.715 0)
      (effects (font (size 1.27 1.27)) hide)
    )
    (property "Value" "GND" (at 154.94 257.175 0)
      (effects (font (size 1.27 1.27)))
    )
    (property "Footprint" "" (at 154.94 253.365 0)
      (effects (font (size 1.27 1.27)) hide)
    )
    (property "Datasheet" "" (at 154.94 253.365 0)
      (effects (font (size 1.27 1.27)) hide)
    )
    (property "Author" "Antmicro" (at 163.83 260.985 0)
      (effects (font (size 1.27 1.27) (thickness 0.15)) (justify left bottom) hide)
    )
    (property "License" "Apache-2.0" (at 163.83 263.525 0)
      (effects (font (size 1.27 1.27) (thickness 0.15)) (justify left bottom) hide)
    )
    (pin "1")
    (instances
      (project "data-center-rdimm-ddr4-tester"
        (path ""
          (reference "#PWR0346") (unit 1)
        )
      )
    )
  )

  (symbol (lib_id "antmicroResistors0402:R_10k_0402") (at 139.7 188.595 90) (unit 1)
    (in_bom yes) (on_board yes) (dnp no) (fields_autoplaced)
    (property "Reference" "R209" (at 142.24 184.785 90)
      (effects (font (size 1.524 1.524)) (justify right))
    )
    (property "Value" "R_10k_0402" (at 152.4 168.275 0)
      (effects (font (size 1.27 1.27) (thickness 0.15)) (justify left bottom) hide)
    )
    (property "Footprint" "antmicro-footprints:R_0402_1005Metric" (at 154.94 168.275 0)
      (effects (font (size 1.27 1.27) (thickness 0.15)) (justify left bottom) hide)
    )
    (property "Datasheet" "https://www.bourns.com/docs/product-datasheets/cr.pdf" (at 157.48 168.275 0)
      (effects (font (size 1.27 1.27) (thickness 0.15)) (justify left bottom) hide)
    )
    (property "Manufacturer" "Bourns" (at 162.56 168.275 0)
      (effects (font (size 1.27 1.27) (thickness 0.15)) (justify left bottom) hide)
    )
    (property "MPN" "CR0402-FX-1002GLF" (at 160.02 168.275 0)
      (effects (font (size 1.27 1.27) (thickness 0.15)) (justify left bottom) hide)
    )
    (property "Val" "10k" (at 142.24 187.9599 90)
      (effects (font (size 1.27 1.27) (thickness 0.15)) (justify right))
    )
    (property "License" "Apache-2.0" (at 165.1 168.275 0)
      (effects (font (size 1.27 1.27) (thickness 0.15)) (justify left bottom) hide)
    )
    (property "Author" "Antmicro" (at 167.64 168.275 0)
      (effects (font (size 1.27 1.27) (thickness 0.15)) (justify left bottom) hide)
    )
    (property "Tolerance" "1%" (at 149.86 168.275 0)
      (effects (font (size 1.27 1.27)) (justify left bottom) hide)
    )
    (pin "1")
    (pin "2")
    (instances
      (project "data-center-rdimm-ddr4-tester"
        (path ""
          (reference "R209") (unit 1)
        )
      )
    )
  )

  (symbol (lib_id "antmicroResistors0402:R_33R_0402") (at 344.17 64.135 0) (unit 1)
    (in_bom yes) (on_board yes) (dnp no)
    (property "Reference" "R150" (at 341.63 62.865 0)
      (effects (font (size 1.524 1.524)))
    )
    (property "Value" "R_33R_0402" (at 364.49 76.835 0)
      (effects (font (size 1.27 1.27) (thickness 0.15)) (justify left bottom) hide)
    )
    (property "Footprint" "antmicro-footprints:R_0402_1005Metric" (at 364.49 79.375 0)
      (effects (font (size 1.27 1.27) (thickness 0.15)) (justify left bottom) hide)
    )
    (property "Datasheet" "https://www.bourns.com/docs/product-datasheets/cr.pdf" (at 364.49 81.915 0)
      (effects (font (size 1.27 1.27) (thickness 0.15)) (justify left bottom) hide)
    )
    (property "Manufacturer" "Bourns" (at 364.49 86.995 0)
      (effects (font (size 1.27 1.27) (thickness 0.15)) (justify left bottom) hide)
    )
    (property "MPN" "CR0402-FX-33R0GLF" (at 364.49 84.455 0)
      (effects (font (size 1.27 1.27) (thickness 0.15)) (justify left bottom) hide)
    )
    (property "Val" "33R" (at 351.155 62.865 0)
      (effects (font (size 1.27 1.27) (thickness 0.15)))
    )
    (property "License" "Apache-2.0" (at 364.49 89.535 0)
      (effects (font (size 1.27 1.27) (thickness 0.15)) (justify left bottom) hide)
    )
    (property "Author" "Antmicro" (at 364.49 92.075 0)
      (effects (font (size 1.27 1.27) (thickness 0.15)) (justify left bottom) hide)
    )
    (property "Tolerance" "1%" (at 364.49 74.295 0)
      (effects (font (size 1.27 1.27)) (justify left bottom) hide)
    )
    (pin "1")
    (pin "2")
    (instances
      (project "data-center-rdimm-ddr4-tester"
        (path ""
          (reference "R150") (unit 1)
        )
      )
    )
  )

  (symbol (lib_id "antmicroCapacitors0402:C_100n_0402") (at 349.25 116.205 0) (unit 1)
    (in_bom yes) (on_board yes) (dnp no)
    (property "Reference" "C264" (at 347.98 114.935 0)
      (effects (font (size 1.524 1.524)))
    )
    (property "Value" "C_100n_0402" (at 369.57 126.365 0)
      (effects (font (size 1.27 1.27) (thickness 0.15)) (justify left bottom) hide)
    )
    (property "Footprint" "antmicro-footprints:C_0402_1005Metric" (at 369.57 128.905 0)
      (effects (font (size 1.27 1.27) (thickness 0.15)) (justify left bottom) hide)
    )
    (property "Datasheet" "https://search.murata.co.jp/Ceramy/image/img/A01X/G101/ENG/GRM155R61H104KE14-01.pdf" (at 369.57 131.445 0)
      (effects (font (size 1.27 1.27) (thickness 0.15)) (justify left bottom) hide)
    )
    (property "Manufacturer" "Murata" (at 369.57 136.525 0)
      (effects (font (size 1.27 1.27) (thickness 0.15)) (justify left bottom) hide)
    )
    (property "MPN" "GRM155R61H104KE14D" (at 369.57 133.985 0)
      (effects (font (size 1.27 1.27) (thickness 0.15)) (justify left bottom) hide)
    )
    (property "Val" "100n" (at 354.965 114.935 0)
      (effects (font (size 1.27 1.27) (thickness 0.15)))
    )
    (property "License" "Apache-2.0" (at 369.57 139.065 0)
      (effects (font (size 1.27 1.27) (thickness 0.15)) (justify left bottom) hide)
    )
    (property "Author" "Antmicro" (at 369.57 141.605 0)
      (effects (font (size 1.27 1.27) (thickness 0.15)) (justify left bottom) hide)
    )
    (property "Voltage" "50V" (at 369.57 144.145 0)
      (effects (font (size 1.27 1.27)) (justify left bottom) hide)
    )
    (property "Dielectric" "X5R" (at 369.57 146.685 0)
      (effects (font (size 1.27 1.27)) (justify left bottom) hide)
    )
    (pin "1")
    (pin "2")
    (instances
      (project "data-center-rdimm-ddr4-tester"
        (path ""
          (reference "C264") (unit 1)
        )
      )
    )
  )

  (symbol (lib_id "antmicroResistors0402:R_33R_0402") (at 344.17 46.99 0) (unit 1)
    (in_bom yes) (on_board yes) (dnp no)
    (property "Reference" "R211" (at 341.63 45.72 0)
      (effects (font (size 1.524 1.524)))
    )
    (property "Value" "R_33R_0402" (at 364.49 59.69 0)
      (effects (font (size 1.27 1.27) (thickness 0.15)) (justify left bottom) hide)
    )
    (property "Footprint" "antmicro-footprints:R_0402_1005Metric" (at 364.49 62.23 0)
      (effects (font (size 1.27 1.27) (thickness 0.15)) (justify left bottom) hide)
    )
    (property "Datasheet" "https://www.bourns.com/docs/product-datasheets/cr.pdf" (at 364.49 64.77 0)
      (effects (font (size 1.27 1.27) (thickness 0.15)) (justify left bottom) hide)
    )
    (property "Manufacturer" "Bourns" (at 364.49 69.85 0)
      (effects (font (size 1.27 1.27) (thickness 0.15)) (justify left bottom) hide)
    )
    (property "MPN" "CR0402-FX-33R0GLF" (at 364.49 67.31 0)
      (effects (font (size 1.27 1.27) (thickness 0.15)) (justify left bottom) hide)
    )
    (property "Val" "33R" (at 351.155 45.72 0)
      (effects (font (size 1.27 1.27) (thickness 0.15)))
    )
    (property "License" "Apache-2.0" (at 364.49 72.39 0)
      (effects (font (size 1.27 1.27) (thickness 0.15)) (justify left bottom) hide)
    )
    (property "Author" "Antmicro" (at 364.49 74.93 0)
      (effects (font (size 1.27 1.27) (thickness 0.15)) (justify left bottom) hide)
    )
    (property "Tolerance" "1%" (at 364.49 57.15 0)
      (effects (font (size 1.27 1.27)) (justify left bottom) hide)
    )
    (pin "1")
    (pin "2")
    (instances
      (project "data-center-rdimm-ddr4-tester"
        (path ""
          (reference "R211") (unit 1)
        )
      )
    )
  )

  (symbol (lib_id "antmicroTestPoints:TP_0.75mm_SMD") (at 154.305 41.275 180) (unit 1)
    (in_bom yes) (on_board yes) (dnp no)
    (property "Reference" "TP19" (at 147.32 41.275 0)
      (effects (font (size 1.27 1.27)))
    )
    (property "Value" "TP_0.75mm_SMD" (at 139.065 33.655 0)
      (effects (font (size 1.27 1.27) (thickness 0.15)) (justify left bottom) hide)
    )
    (property "Footprint" "antmicro-footprints:TP_SMD_0.75mm" (at 139.065 31.115 0)
      (effects (font (size 1.27 1.27) (thickness 0.15)) (justify left bottom) hide)
    )
    (property "Datasheet" "" (at 139.065 28.575 0)
      (effects (font (size 1.27 1.27) (thickness 0.15)) (justify left bottom) hide)
    )
    (property "MPN" "" (at 154.305 41.275 0)
      (effects (font (size 1.27 1.27)) hide)
    )
    (property "Manufacturer" "" (at 154.305 41.275 0)
      (effects (font (size 1.27 1.27)) hide)
    )
    (property "Author" "Antmicro" (at 139.065 26.035 0)
      (effects (font (size 1.27 1.27) (thickness 0.15)) (justify left bottom) hide)
    )
    (property "License" "Apache-2.0" (at 139.065 23.495 0)
      (effects (font (size 1.27 1.27) (thickness 0.15)) (justify left bottom) hide)
    )
    (pin "1")
    (instances
      (project "data-center-rdimm-ddr4-tester"
        (path ""
          (reference "TP19") (unit 1)
        )
      )
    )
  )

  (symbol (lib_id "antmicroFMCConnectors:ASP-134486-01") (at 156.845 41.275 0) (unit 3)
    (in_bom yes) (on_board yes) (dnp no) (fields_autoplaced)
    (property "Reference" "J5" (at 172.085 33.655 0)
      (effects (font (size 1.27 1.27)))
    )
    (property "Value" "ASP-134486-01" (at 172.085 36.195 0)
      (effects (font (size 1.27 1.27) (thickness 0.15)))
    )
    (property "Footprint" "antmicro-footprints:FMC_SAMTEC_ASP-134486-01" (at 202.565 52.705 0)
      (effects (font (size 1.27 1.27) (thickness 0.15)) (justify left bottom) hide)
    )
    (property "Datasheet" "https://suddendocs.samtec.com/prints/asp-134486-01-mkt.pdf?_gl=1*a2d3qa*_ga*MzYxMTM5My4xNjYzOTI3MDkz*_ga_3KFNZC07WW*MTY2NDIwMTUxMC4zLjAuMTY2NDIwMTUxMC42MC4wLjA." (at 202.565 55.245 0)
      (effects (font (size 1.27 1.27) (thickness 0.15)) (justify left bottom) hide)
    )
    (property "Manufacturer" "Samtec" (at 202.565 57.785 0)
      (effects (font (size 1.27 1.27) (thickness 0.15)) (justify left bottom) hide)
    )
    (property "MPN" "ASP-134486-01" (at 202.565 60.325 0)
      (effects (font (size 1.27 1.27) (thickness 0.15)) (justify left bottom) hide)
    )
    (property "Author" "Antmicro" (at 202.565 62.865 0)
      (effects (font (size 1.27 1.27) (thickness 0.15)) (justify left bottom) hide)
    )
    (property "License" "Apache-2.0" (at 202.565 65.405 0)
      (effects (font (size 1.27 1.27) (thickness 0.15)) (justify left bottom) hide)
    )
    (pin "J1")
    (pin "J10")
    (pin "J11")
    (pin "J12")
    (pin "J13")
    (pin "J14")
    (pin "J15")
    (pin "J16")
    (pin "J17")
    (pin "J18")
    (pin "J19")
    (pin "J2")
    (pin "J20")
    (pin "J21")
    (pin "J22")
    (pin "J23")
    (pin "J24")
    (pin "J25")
    (pin "J26")
    (pin "J27")
    (pin "J28")
    (pin "J29")
    (pin "J3")
    (pin "J30")
    (pin "J31")
    (pin "J32")
    (pin "J33")
    (pin "J34")
    (pin "J35")
    (pin "J36")
    (pin "J37")
    (pin "J38")
    (pin "J39")
    (pin "J4")
    (pin "J40")
    (pin "J5")
    (pin "J6")
    (pin "J7")
    (pin "J8")
    (pin "J9")
    (pin "K1")
    (pin "K10")
    (pin "K11")
    (pin "K12")
    (pin "K13")
    (pin "K14")
    (pin "K15")
    (pin "K16")
    (pin "K17")
    (pin "K18")
    (pin "K19")
    (pin "K2")
    (pin "K20")
    (pin "K21")
    (pin "K22")
    (pin "K23")
    (pin "K24")
    (pin "K25")
    (pin "K26")
    (pin "K27")
    (pin "K28")
    (pin "K29")
    (pin "K3")
    (pin "K30")
    (pin "K31")
    (pin "K32")
    (pin "K33")
    (pin "K34")
    (pin "K35")
    (pin "K36")
    (pin "K37")
    (pin "K38")
    (pin "K39")
    (pin "K4")
    (pin "K40")
    (pin "K5")
    (pin "K6")
    (pin "K7")
    (pin "K8")
    (pin "K9")
    (pin "G1")
    (pin "G10")
    (pin "G11")
    (pin "G12")
    (pin "G13")
    (pin "G14")
    (pin "G15")
    (pin "G16")
    (pin "G17")
    (pin "G18")
    (pin "G19")
    (pin "G2")
    (pin "G20")
    (pin "G21")
    (pin "G22")
    (pin "G23")
    (pin "G24")
    (pin "G25")
    (pin "G26")
    (pin "G27")
    (pin "G28")
    (pin "G29")
    (pin "G3")
    (pin "G30")
    (pin "G31")
    (pin "G32")
    (pin "G33")
    (pin "G34")
    (pin "G35")
    (pin "G36")
    (pin "G37")
    (pin "G38")
    (pin "G39")
    (pin "G4")
    (pin "G40")
    (pin "G5")
    (pin "G6")
    (pin "G7")
    (pin "G8")
    (pin "G9")
    (pin "H1")
    (pin "H10")
    (pin "H11")
    (pin "H12")
    (pin "H13")
    (pin "H14")
    (pin "H15")
    (pin "H16")
    (pin "H17")
    (pin "H18")
    (pin "H19")
    (pin "H2")
    (pin "H20")
    (pin "H21")
    (pin "H22")
    (pin "H23")
    (pin "H24")
    (pin "H25")
    (pin "H26")
    (pin "H27")
    (pin "H28")
    (pin "H29")
    (pin "H3")
    (pin "H30")
    (pin "H31")
    (pin "H32")
    (pin "H33")
    (pin "H34")
    (pin "H35")
    (pin "H36")
    (pin "H37")
    (pin "H38")
    (pin "H39")
    (pin "H4")
    (pin "H40")
    (pin "H5")
    (pin "H6")
    (pin "H7")
    (pin "H8")
    (pin "H9")
    (pin "E1")
    (pin "E10")
    (pin "E11")
    (pin "E12")
    (pin "E13")
    (pin "E14")
    (pin "E15")
    (pin "E16")
    (pin "E17")
    (pin "E18")
    (pin "E19")
    (pin "E2")
    (pin "E20")
    (pin "E21")
    (pin "E22")
    (pin "E23")
    (pin "E24")
    (pin "E25")
    (pin "E26")
    (pin "E27")
    (pin "E28")
    (pin "E29")
    (pin "E3")
    (pin "E30")
    (pin "E31")
    (pin "E32")
    (pin "E33")
    (pin "E34")
    (pin "E35")
    (pin "E36")
    (pin "E37")
    (pin "E38")
    (pin "E39")
    (pin "E4")
    (pin "E40")
    (pin "E5")
    (pin "E6")
    (pin "E7")
    (pin "E8")
    (pin "E9")
    (pin "F1")
    (pin "F10")
    (pin "F11")
    (pin "F12")
    (pin "F13")
    (pin "F14")
    (pin "F15")
    (pin "F16")
    (pin "F17")
    (pin "F18")
    (pin "F19")
    (pin "F2")
    (pin "F20")
    (pin "F21")
    (pin "F22")
    (pin "F23")
    (pin "F24")
    (pin "F25")
    (pin "F26")
    (pin "F27")
    (pin "F28")
    (pin "F29")
    (pin "F3")
    (pin "F30")
    (pin "F31")
    (pin "F32")
    (pin "F33")
    (pin "F34")
    (pin "F35")
    (pin "F36")
    (pin "F37")
    (pin "F38")
    (pin "F39")
    (pin "F4")
    (pin "F40")
    (pin "F5")
    (pin "F6")
    (pin "F7")
    (pin "F8")
    (pin "F9")
    (pin "C1")
    (pin "C10")
    (pin "C11")
    (pin "C12")
    (pin "C13")
    (pin "C14")
    (pin "C15")
    (pin "C16")
    (pin "C17")
    (pin "C18")
    (pin "C19")
    (pin "C2")
    (pin "C20")
    (pin "C21")
    (pin "C22")
    (pin "C23")
    (pin "C24")
    (pin "C25")
    (pin "C26")
    (pin "C27")
    (pin "C28")
    (pin "C29")
    (pin "C3")
    (pin "C30")
    (pin "C31")
    (pin "C32")
    (pin "C33")
    (pin "C34")
    (pin "C35")
    (pin "C36")
    (pin "C37")
    (pin "C38")
    (pin "C39")
    (pin "C4")
    (pin "C40")
    (pin "C5")
    (pin "C6")
    (pin "C7")
    (pin "C8")
    (pin "C9")
    (pin "D1")
    (pin "D10")
    (pin "D11")
    (pin "D12")
    (pin "D13")
    (pin "D14")
    (pin "D15")
    (pin "D16")
    (pin "D17")
    (pin "D18")
    (pin "D19")
    (pin "D2")
    (pin "D20")
    (pin "D21")
    (pin "D22")
    (pin "D23")
    (pin "D24")
    (pin "D25")
    (pin "D26")
    (pin "D27")
    (pin "D28")
    (pin "D29")
    (pin "D3")
    (pin "D30")
    (pin "D31")
    (pin "D32")
    (pin "D33")
    (pin "D34")
    (pin "D35")
    (pin "D36")
    (pin "D37")
    (pin "D38")
    (pin "D39")
    (pin "D4")
    (pin "D40")
    (pin "D5")
    (pin "D6")
    (pin "D7")
    (pin "D8")
    (pin "D9")
    (pin "A1")
    (pin "A10")
    (pin "A11")
    (pin "A12")
    (pin "A13")
    (pin "A14")
    (pin "A15")
    (pin "A16")
    (pin "A17")
    (pin "A18")
    (pin "A19")
    (pin "A2")
    (pin "A20")
    (pin "A21")
    (pin "A22")
    (pin "A23")
    (pin "A24")
    (pin "A25")
    (pin "A26")
    (pin "A27")
    (pin "A28")
    (pin "A29")
    (pin "A3")
    (pin "A30")
    (pin "A31")
    (pin "A32")
    (pin "A33")
    (pin "A34")
    (pin "A35")
    (pin "A36")
    (pin "A37")
    (pin "A38")
    (pin "A39")
    (pin "A4")
    (pin "A40")
    (pin "A5")
    (pin "A6")
    (pin "A7")
    (pin "A8")
    (pin "A9")
    (pin "B1")
    (pin "B10")
    (pin "B11")
    (pin "B12")
    (pin "B13")
    (pin "B14")
    (pin "B15")
    (pin "B16")
    (pin "B17")
    (pin "B18")
    (pin "B19")
    (pin "B2")
    (pin "B20")
    (pin "B21")
    (pin "B22")
    (pin "B23")
    (pin "B24")
    (pin "B25")
    (pin "B26")
    (pin "B27")
    (pin "B28")
    (pin "B29")
    (pin "B3")
    (pin "B30")
    (pin "B31")
    (pin "B32")
    (pin "B33")
    (pin "B34")
    (pin "B35")
    (pin "B36")
    (pin "B37")
    (pin "B38")
    (pin "B39")
    (pin "B4")
    (pin "B40")
    (pin "B5")
    (pin "B6")
    (pin "B7")
    (pin "B8")
    (pin "B9")
    (instances
      (project "data-center-rdimm-ddr4-tester"
        (path ""
          (reference "J5") (unit 3)
        )
      )
    )
  )

  (symbol (lib_id "antmicroFMCConnectors:ASP-134486-01") (at 64.135 41.91 0) (unit 1)
    (in_bom yes) (on_board yes) (dnp no) (fields_autoplaced)
    (property "Reference" "J5" (at 79.375 34.29 0)
      (effects (font (size 1.27 1.27)))
    )
    (property "Value" "ASP-134486-01" (at 79.375 36.83 0)
      (effects (font (size 1.27 1.27) (thickness 0.15)))
    )
    (property "Footprint" "antmicro-footprints:FMC_SAMTEC_ASP-134486-01" (at 109.855 53.34 0)
      (effects (font (size 1.27 1.27) (thickness 0.15)) (justify left bottom) hide)
    )
    (property "Datasheet" "https://suddendocs.samtec.com/prints/asp-134486-01-mkt.pdf?_gl=1*a2d3qa*_ga*MzYxMTM5My4xNjYzOTI3MDkz*_ga_3KFNZC07WW*MTY2NDIwMTUxMC4zLjAuMTY2NDIwMTUxMC42MC4wLjA." (at 109.855 55.88 0)
      (effects (font (size 1.27 1.27) (thickness 0.15)) (justify left bottom) hide)
    )
    (property "Manufacturer" "Samtec" (at 109.855 58.42 0)
      (effects (font (size 1.27 1.27) (thickness 0.15)) (justify left bottom) hide)
    )
    (property "MPN" "ASP-134486-01" (at 109.855 60.96 0)
      (effects (font (size 1.27 1.27) (thickness 0.15)) (justify left bottom) hide)
    )
    (property "Author" "Antmicro" (at 109.855 63.5 0)
      (effects (font (size 1.27 1.27) (thickness 0.15)) (justify left bottom) hide)
    )
    (property "License" "Apache-2.0" (at 109.855 66.04 0)
      (effects (font (size 1.27 1.27) (thickness 0.15)) (justify left bottom) hide)
    )
    (pin "J1")
    (pin "J10")
    (pin "J11")
    (pin "J12")
    (pin "J13")
    (pin "J14")
    (pin "J15")
    (pin "J16")
    (pin "J17")
    (pin "J18")
    (pin "J19")
    (pin "J2")
    (pin "J20")
    (pin "J21")
    (pin "J22")
    (pin "J23")
    (pin "J24")
    (pin "J25")
    (pin "J26")
    (pin "J27")
    (pin "J28")
    (pin "J29")
    (pin "J3")
    (pin "J30")
    (pin "J31")
    (pin "J32")
    (pin "J33")
    (pin "J34")
    (pin "J35")
    (pin "J36")
    (pin "J37")
    (pin "J38")
    (pin "J39")
    (pin "J4")
    (pin "J40")
    (pin "J5")
    (pin "J6")
    (pin "J7")
    (pin "J8")
    (pin "J9")
    (pin "K1")
    (pin "K10")
    (pin "K11")
    (pin "K12")
    (pin "K13")
    (pin "K14")
    (pin "K15")
    (pin "K16")
    (pin "K17")
    (pin "K18")
    (pin "K19")
    (pin "K2")
    (pin "K20")
    (pin "K21")
    (pin "K22")
    (pin "K23")
    (pin "K24")
    (pin "K25")
    (pin "K26")
    (pin "K27")
    (pin "K28")
    (pin "K29")
    (pin "K3")
    (pin "K30")
    (pin "K31")
    (pin "K32")
    (pin "K33")
    (pin "K34")
    (pin "K35")
    (pin "K36")
    (pin "K37")
    (pin "K38")
    (pin "K39")
    (pin "K4")
    (pin "K40")
    (pin "K5")
    (pin "K6")
    (pin "K7")
    (pin "K8")
    (pin "K9")
    (pin "G1")
    (pin "G10")
    (pin "G11")
    (pin "G12")
    (pin "G13")
    (pin "G14")
    (pin "G15")
    (pin "G16")
    (pin "G17")
    (pin "G18")
    (pin "G19")
    (pin "G2")
    (pin "G20")
    (pin "G21")
    (pin "G22")
    (pin "G23")
    (pin "G24")
    (pin "G25")
    (pin "G26")
    (pin "G27")
    (pin "G28")
    (pin "G29")
    (pin "G3")
    (pin "G30")
    (pin "G31")
    (pin "G32")
    (pin "G33")
    (pin "G34")
    (pin "G35")
    (pin "G36")
    (pin "G37")
    (pin "G38")
    (pin "G39")
    (pin "G4")
    (pin "G40")
    (pin "G5")
    (pin "G6")
    (pin "G7")
    (pin "G8")
    (pin "G9")
    (pin "H1")
    (pin "H10")
    (pin "H11")
    (pin "H12")
    (pin "H13")
    (pin "H14")
    (pin "H15")
    (pin "H16")
    (pin "H17")
    (pin "H18")
    (pin "H19")
    (pin "H2")
    (pin "H20")
    (pin "H21")
    (pin "H22")
    (pin "H23")
    (pin "H24")
    (pin "H25")
    (pin "H26")
    (pin "H27")
    (pin "H28")
    (pin "H29")
    (pin "H3")
    (pin "H30")
    (pin "H31")
    (pin "H32")
    (pin "H33")
    (pin "H34")
    (pin "H35")
    (pin "H36")
    (pin "H37")
    (pin "H38")
    (pin "H39")
    (pin "H4")
    (pin "H40")
    (pin "H5")
    (pin "H6")
    (pin "H7")
    (pin "H8")
    (pin "H9")
    (pin "E1")
    (pin "E10")
    (pin "E11")
    (pin "E12")
    (pin "E13")
    (pin "E14")
    (pin "E15")
    (pin "E16")
    (pin "E17")
    (pin "E18")
    (pin "E19")
    (pin "E2")
    (pin "E20")
    (pin "E21")
    (pin "E22")
    (pin "E23")
    (pin "E24")
    (pin "E25")
    (pin "E26")
    (pin "E27")
    (pin "E28")
    (pin "E29")
    (pin "E3")
    (pin "E30")
    (pin "E31")
    (pin "E32")
    (pin "E33")
    (pin "E34")
    (pin "E35")
    (pin "E36")
    (pin "E37")
    (pin "E38")
    (pin "E39")
    (pin "E4")
    (pin "E40")
    (pin "E5")
    (pin "E6")
    (pin "E7")
    (pin "E8")
    (pin "E9")
    (pin "F1")
    (pin "F10")
    (pin "F11")
    (pin "F12")
    (pin "F13")
    (pin "F14")
    (pin "F15")
    (pin "F16")
    (pin "F17")
    (pin "F18")
    (pin "F19")
    (pin "F2")
    (pin "F20")
    (pin "F21")
    (pin "F22")
    (pin "F23")
    (pin "F24")
    (pin "F25")
    (pin "F26")
    (pin "F27")
    (pin "F28")
    (pin "F29")
    (pin "F3")
    (pin "F30")
    (pin "F31")
    (pin "F32")
    (pin "F33")
    (pin "F34")
    (pin "F35")
    (pin "F36")
    (pin "F37")
    (pin "F38")
    (pin "F39")
    (pin "F4")
    (pin "F40")
    (pin "F5")
    (pin "F6")
    (pin "F7")
    (pin "F8")
    (pin "F9")
    (pin "C1")
    (pin "C10")
    (pin "C11")
    (pin "C12")
    (pin "C13")
    (pin "C14")
    (pin "C15")
    (pin "C16")
    (pin "C17")
    (pin "C18")
    (pin "C19")
    (pin "C2")
    (pin "C20")
    (pin "C21")
    (pin "C22")
    (pin "C23")
    (pin "C24")
    (pin "C25")
    (pin "C26")
    (pin "C27")
    (pin "C28")
    (pin "C29")
    (pin "C3")
    (pin "C30")
    (pin "C31")
    (pin "C32")
    (pin "C33")
    (pin "C34")
    (pin "C35")
    (pin "C36")
    (pin "C37")
    (pin "C38")
    (pin "C39")
    (pin "C4")
    (pin "C40")
    (pin "C5")
    (pin "C6")
    (pin "C7")
    (pin "C8")
    (pin "C9")
    (pin "D1")
    (pin "D10")
    (pin "D11")
    (pin "D12")
    (pin "D13")
    (pin "D14")
    (pin "D15")
    (pin "D16")
    (pin "D17")
    (pin "D18")
    (pin "D19")
    (pin "D2")
    (pin "D20")
    (pin "D21")
    (pin "D22")
    (pin "D23")
    (pin "D24")
    (pin "D25")
    (pin "D26")
    (pin "D27")
    (pin "D28")
    (pin "D29")
    (pin "D3")
    (pin "D30")
    (pin "D31")
    (pin "D32")
    (pin "D33")
    (pin "D34")
    (pin "D35")
    (pin "D36")
    (pin "D37")
    (pin "D38")
    (pin "D39")
    (pin "D4")
    (pin "D40")
    (pin "D5")
    (pin "D6")
    (pin "D7")
    (pin "D8")
    (pin "D9")
    (pin "A1")
    (pin "A10")
    (pin "A11")
    (pin "A12")
    (pin "A13")
    (pin "A14")
    (pin "A15")
    (pin "A16")
    (pin "A17")
    (pin "A18")
    (pin "A19")
    (pin "A2")
    (pin "A20")
    (pin "A21")
    (pin "A22")
    (pin "A23")
    (pin "A24")
    (pin "A25")
    (pin "A26")
    (pin "A27")
    (pin "A28")
    (pin "A29")
    (pin "A3")
    (pin "A30")
    (pin "A31")
    (pin "A32")
    (pin "A33")
    (pin "A34")
    (pin "A35")
    (pin "A36")
    (pin "A37")
    (pin "A38")
    (pin "A39")
    (pin "A4")
    (pin "A40")
    (pin "A5")
    (pin "A6")
    (pin "A7")
    (pin "A8")
    (pin "A9")
    (pin "B1")
    (pin "B10")
    (pin "B11")
    (pin "B12")
    (pin "B13")
    (pin "B14")
    (pin "B15")
    (pin "B16")
    (pin "B17")
    (pin "B18")
    (pin "B19")
    (pin "B2")
    (pin "B20")
    (pin "B21")
    (pin "B22")
    (pin "B23")
    (pin "B24")
    (pin "B25")
    (pin "B26")
    (pin "B27")
    (pin "B28")
    (pin "B29")
    (pin "B3")
    (pin "B30")
    (pin "B31")
    (pin "B32")
    (pin "B33")
    (pin "B34")
    (pin "B35")
    (pin "B36")
    (pin "B37")
    (pin "B38")
    (pin "B39")
    (pin "B4")
    (pin "B40")
    (pin "B5")
    (pin "B6")
    (pin "B7")
    (pin "B8")
    (pin "B9")
    (instances
      (project "data-center-rdimm-ddr4-tester"
        (path ""
          (reference "J5") (unit 1)
        )
      )
    )
  )

  (symbol (lib_id "antmicroResistors0402:R_10k_0402") (at 153.67 169.545 180) (unit 1)
    (in_bom yes) (on_board yes) (dnp no)
    (property "Reference" "R154" (at 151.13 164.465 0)
      (effects (font (size 1.524 1.524)))
    )
    (property "Value" "R_10k_0402" (at 133.35 156.845 0)
      (effects (font (size 1.27 1.27) (thickness 0.15)) (justify left bottom) hide)
    )
    (property "Footprint" "antmicro-footprints:R_0402_1005Metric" (at 133.35 154.305 0)
      (effects (font (size 1.27 1.27) (thickness 0.15)) (justify left bottom) hide)
    )
    (property "Datasheet" "https://www.bourns.com/docs/product-datasheets/cr.pdf" (at 133.35 151.765 0)
      (effects (font (size 1.27 1.27) (thickness 0.15)) (justify left bottom) hide)
    )
    (property "Manufacturer" "Bourns" (at 133.35 146.685 0)
      (effects (font (size 1.27 1.27) (thickness 0.15)) (justify left bottom) hide)
    )
    (property "MPN" "CR0402-FX-1002GLF" (at 133.35 149.225 0)
      (effects (font (size 1.27 1.27) (thickness 0.15)) (justify left bottom) hide)
    )
    (property "Val" "10k" (at 151.13 167.005 0)
      (effects (font (size 1.27 1.27) (thickness 0.15)))
    )
    (property "License" "Apache-2.0" (at 133.35 144.145 0)
      (effects (font (size 1.27 1.27) (thickness 0.15)) (justify left bottom) hide)
    )
    (property "Author" "Antmicro" (at 133.35 141.605 0)
      (effects (font (size 1.27 1.27) (thickness 0.15)) (justify left bottom) hide)
    )
    (property "Tolerance" "1%" (at 133.35 159.385 0)
      (effects (font (size 1.27 1.27)) (justify left bottom) hide)
    )
    (pin "1")
    (pin "2")
    (instances
      (project "data-center-rdimm-ddr4-tester"
        (path ""
          (reference "R154") (unit 1)
        )
      )
    )
  )

  (symbol (lib_id "antmicroCapacitorsmisc:C_100n_0201") (at 231.14 246.38 270) (unit 1)
    (in_bom yes) (on_board yes) (dnp no)
    (property "Reference" "C257" (at 231.775 247.015 90)
      (effects (font (size 1.524 1.524)) (justify left))
    )
    (property "Value" "C_100n_0201" (at 220.98 266.7 0)
      (effects (font (size 1.27 1.27) (thickness 0.15)) (justify left bottom) hide)
    )
    (property "Footprint" "antmicro-footprints:C_0201" (at 218.44 266.7 0)
      (effects (font (size 1.27 1.27) (thickness 0.15)) (justify left bottom) hide)
    )
    (property "Datasheet" " " (at 215.9 266.7 0)
      (effects (font (size 1.27 1.27) (thickness 0.15)) (justify left bottom) hide)
    )
    (property "Manufacturer" "Yaego" (at 210.82 266.7 0)
      (effects (font (size 1.27 1.27) (thickness 0.15)) (justify left bottom) hide)
    )
    (property "MPN" "CC0201KRX6S5BB104" (at 213.36 266.7 0)
      (effects (font (size 1.27 1.27) (thickness 0.15)) (justify left bottom) hide)
    )
    (property "Val" "100n" (at 231.775 250.825 90)
      (effects (font (size 1.27 1.27) (thickness 0.15)) (justify left))
    )
    (property "License" "Apache-2.0" (at 208.28 266.7 0)
      (effects (font (size 1.27 1.27) (thickness 0.15)) (justify left bottom) hide)
    )
    (property "Author" "Antmicro" (at 205.74 266.7 0)
      (effects (font (size 1.27 1.27) (thickness 0.15)) (justify left bottom) hide)
    )
    (property "Voltage" "" (at 203.2 266.7 0)
      (effects (font (size 1.27 1.27)) (justify left bottom) hide)
    )
    (property "Dielectric" "" (at 200.66 266.7 0)
      (effects (font (size 1.27 1.27)) (justify left bottom) hide)
    )
    (pin "1")
    (pin "2")
    (instances
      (project "data-center-rdimm-ddr4-tester"
        (path ""
          (reference "C257") (unit 1)
        )
      )
    )
  )

  (symbol (lib_id "antmicroDiodesRectifiersSingle:PDS760") (at 196.215 245.11 0) (unit 1)
    (in_bom yes) (on_board yes) (dnp no)
    (property "Reference" "D18" (at 200.025 240.665 0)
      (effects (font (size 1.524 1.524)))
    )
    (property "Value" "PDS760" (at 200.025 242.57 0)
      (effects (font (size 1.27 1.27) (thickness 0.15)))
    )
    (property "Footprint" "antmicro-footprints:PowerDI5" (at 219.075 255.27 0)
      (effects (font (size 1.27 1.27) (thickness 0.15)) (justify left bottom) hide)
    )
    (property "Datasheet" "https://www.diodes.com/assets/Datasheets/ds30470.pdf" (at 219.075 257.81 0)
      (effects (font (size 1.27 1.27) (thickness 0.15)) (justify left bottom) hide)
    )
    (property "Manufacturer" "Diodes Incorporated" (at 219.075 260.35 0)
      (effects (font (size 1.27 1.27) (thickness 0.15)) (justify left bottom) hide)
    )
    (property "MPN" "PDS760-13" (at 219.075 262.89 0)
      (effects (font (size 1.27 1.27) (thickness 0.15)) (justify left bottom) hide)
    )
    (property "Author" "Antmicro" (at 219.075 265.43 0)
      (effects (font (size 1.27 1.27) (thickness 0.15)) (justify left bottom) hide)
    )
    (property "License" "Apache-2.0" (at 219.075 267.97 0)
      (effects (font (size 1.27 1.27) (thickness 0.15)) (justify left bottom) hide)
    )
    (pin "A")
    (pin "C")
    (instances
      (project "data-center-rdimm-ddr4-tester"
        (path ""
          (reference "D18") (unit 1)
        )
      )
    )
  )

  (symbol (lib_id "antmicroResistors0402:R_33R_0402") (at 344.17 76.835 0) (unit 1)
    (in_bom yes) (on_board yes) (dnp no)
    (property "Reference" "R153" (at 341.63 75.565 0)
      (effects (font (size 1.524 1.524)))
    )
    (property "Value" "R_33R_0402" (at 364.49 89.535 0)
      (effects (font (size 1.27 1.27) (thickness 0.15)) (justify left bottom) hide)
    )
    (property "Footprint" "antmicro-footprints:R_0402_1005Metric" (at 364.49 92.075 0)
      (effects (font (size 1.27 1.27) (thickness 0.15)) (justify left bottom) hide)
    )
    (property "Datasheet" "https://www.bourns.com/docs/product-datasheets/cr.pdf" (at 364.49 94.615 0)
      (effects (font (size 1.27 1.27) (thickness 0.15)) (justify left bottom) hide)
    )
    (property "Manufacturer" "Bourns" (at 364.49 99.695 0)
      (effects (font (size 1.27 1.27) (thickness 0.15)) (justify left bottom) hide)
    )
    (property "MPN" "CR0402-FX-33R0GLF" (at 364.49 97.155 0)
      (effects (font (size 1.27 1.27) (thickness 0.15)) (justify left bottom) hide)
    )
    (property "Val" "33R" (at 351.155 75.565 0)
      (effects (font (size 1.27 1.27) (thickness 0.15)))
    )
    (property "License" "Apache-2.0" (at 364.49 102.235 0)
      (effects (font (size 1.27 1.27) (thickness 0.15)) (justify left bottom) hide)
    )
    (property "Author" "Antmicro" (at 364.49 104.775 0)
      (effects (font (size 1.27 1.27) (thickness 0.15)) (justify left bottom) hide)
    )
    (property "Tolerance" "1%" (at 364.49 86.995 0)
      (effects (font (size 1.27 1.27)) (justify left bottom) hide)
    )
    (pin "1")
    (pin "2")
    (instances
      (project "data-center-rdimm-ddr4-tester"
        (path ""
          (reference "R153") (unit 1)
        )
      )
    )
  )

  (symbol (lib_id "antmicroCapacitors0402:C_100n_0402") (at 349.25 136.525 0) (unit 1)
    (in_bom yes) (on_board yes) (dnp no)
    (property "Reference" "C268" (at 347.98 135.255 0)
      (effects (font (size 1.524 1.524)))
    )
    (property "Value" "C_100n_0402" (at 369.57 146.685 0)
      (effects (font (size 1.27 1.27) (thickness 0.15)) (justify left bottom) hide)
    )
    (property "Footprint" "antmicro-footprints:C_0402_1005Metric" (at 369.57 149.225 0)
      (effects (font (size 1.27 1.27) (thickness 0.15)) (justify left bottom) hide)
    )
    (property "Datasheet" "https://search.murata.co.jp/Ceramy/image/img/A01X/G101/ENG/GRM155R61H104KE14-01.pdf" (at 369.57 151.765 0)
      (effects (font (size 1.27 1.27) (thickness 0.15)) (justify left bottom) hide)
    )
    (property "Manufacturer" "Murata" (at 369.57 156.845 0)
      (effects (font (size 1.27 1.27) (thickness 0.15)) (justify left bottom) hide)
    )
    (property "MPN" "GRM155R61H104KE14D" (at 369.57 154.305 0)
      (effects (font (size 1.27 1.27) (thickness 0.15)) (justify left bottom) hide)
    )
    (property "Val" "100n" (at 354.965 135.255 0)
      (effects (font (size 1.27 1.27) (thickness 0.15)))
    )
    (property "License" "Apache-2.0" (at 369.57 159.385 0)
      (effects (font (size 1.27 1.27) (thickness 0.15)) (justify left bottom) hide)
    )
    (property "Author" "Antmicro" (at 369.57 161.925 0)
      (effects (font (size 1.27 1.27) (thickness 0.15)) (justify left bottom) hide)
    )
    (property "Voltage" "50V" (at 369.57 164.465 0)
      (effects (font (size 1.27 1.27)) (justify left bottom) hide)
    )
    (property "Dielectric" "X5R" (at 369.57 167.005 0)
      (effects (font (size 1.27 1.27)) (justify left bottom) hide)
    )
    (pin "1")
    (pin "2")
    (instances
      (project "data-center-rdimm-ddr4-tester"
        (path ""
          (reference "C268") (unit 1)
        )
      )
    )
  )

  (symbol (lib_id "antmicropower:GND") (at 238.76 251.46 0) (unit 1)
    (in_bom yes) (on_board yes) (dnp no) (fields_autoplaced)
    (property "Reference" "#PWR0407" (at 238.76 257.81 0)
      (effects (font (size 1.27 1.27)) hide)
    )
    (property "Value" "GND" (at 238.76 255.27 0)
      (effects (font (size 1.27 1.27)))
    )
    (property "Footprint" "" (at 238.76 251.46 0)
      (effects (font (size 1.27 1.27)) hide)
    )
    (property "Datasheet" "" (at 238.76 251.46 0)
      (effects (font (size 1.27 1.27)) hide)
    )
    (property "Author" "Antmicro" (at 247.65 259.08 0)
      (effects (font (size 1.27 1.27) (thickness 0.15)) (justify left bottom) hide)
    )
    (property "License" "Apache-2.0" (at 247.65 261.62 0)
      (effects (font (size 1.27 1.27) (thickness 0.15)) (justify left bottom) hide)
    )
    (pin "1")
    (instances
      (project "data-center-rdimm-ddr4-tester"
        (path ""
          (reference "#PWR0407") (unit 1)
        )
      )
    )
  )

  (symbol (lib_id "antmicroCapacitors0402:C_100n_0402") (at 349.25 106.045 0) (unit 1)
    (in_bom yes) (on_board yes) (dnp no)
    (property "Reference" "C262" (at 347.98 104.775 0)
      (effects (font (size 1.524 1.524)))
    )
    (property "Value" "C_100n_0402" (at 369.57 116.205 0)
      (effects (font (size 1.27 1.27) (thickness 0.15)) (justify left bottom) hide)
    )
    (property "Footprint" "antmicro-footprints:C_0402_1005Metric" (at 369.57 118.745 0)
      (effects (font (size 1.27 1.27) (thickness 0.15)) (justify left bottom) hide)
    )
    (property "Datasheet" "https://search.murata.co.jp/Ceramy/image/img/A01X/G101/ENG/GRM155R61H104KE14-01.pdf" (at 369.57 121.285 0)
      (effects (font (size 1.27 1.27) (thickness 0.15)) (justify left bottom) hide)
    )
    (property "Manufacturer" "Murata" (at 369.57 126.365 0)
      (effects (font (size 1.27 1.27) (thickness 0.15)) (justify left bottom) hide)
    )
    (property "MPN" "GRM155R61H104KE14D" (at 369.57 123.825 0)
      (effects (font (size 1.27 1.27) (thickness 0.15)) (justify left bottom) hide)
    )
    (property "Val" "100n" (at 354.965 104.775 0)
      (effects (font (size 1.27 1.27) (thickness 0.15)))
    )
    (property "License" "Apache-2.0" (at 369.57 128.905 0)
      (effects (font (size 1.27 1.27) (thickness 0.15)) (justify left bottom) hide)
    )
    (property "Author" "Antmicro" (at 369.57 131.445 0)
      (effects (font (size 1.27 1.27) (thickness 0.15)) (justify left bottom) hide)
    )
    (property "Voltage" "50V" (at 369.57 133.985 0)
      (effects (font (size 1.27 1.27)) (justify left bottom) hide)
    )
    (property "Dielectric" "X5R" (at 369.57 136.525 0)
      (effects (font (size 1.27 1.27)) (justify left bottom) hide)
    )
    (pin "1")
    (pin "2")
    (instances
      (project "data-center-rdimm-ddr4-tester"
        (path ""
          (reference "C262") (unit 1)
        )
      )
    )
  )

  (symbol (lib_id "antmicroResistors0402:R_33R_0402") (at 344.17 74.295 0) (unit 1)
    (in_bom yes) (on_board yes) (dnp no)
    (property "Reference" "R152" (at 341.63 73.025 0)
      (effects (font (size 1.524 1.524)))
    )
    (property "Value" "R_33R_0402" (at 364.49 86.995 0)
      (effects (font (size 1.27 1.27) (thickness 0.15)) (justify left bottom) hide)
    )
    (property "Footprint" "antmicro-footprints:R_0402_1005Metric" (at 364.49 89.535 0)
      (effects (font (size 1.27 1.27) (thickness 0.15)) (justify left bottom) hide)
    )
    (property "Datasheet" "https://www.bourns.com/docs/product-datasheets/cr.pdf" (at 364.49 92.075 0)
      (effects (font (size 1.27 1.27) (thickness 0.15)) (justify left bottom) hide)
    )
    (property "Manufacturer" "Bourns" (at 364.49 97.155 0)
      (effects (font (size 1.27 1.27) (thickness 0.15)) (justify left bottom) hide)
    )
    (property "MPN" "CR0402-FX-33R0GLF" (at 364.49 94.615 0)
      (effects (font (size 1.27 1.27) (thickness 0.15)) (justify left bottom) hide)
    )
    (property "Val" "33R" (at 351.155 73.025 0)
      (effects (font (size 1.27 1.27) (thickness 0.15)))
    )
    (property "License" "Apache-2.0" (at 364.49 99.695 0)
      (effects (font (size 1.27 1.27) (thickness 0.15)) (justify left bottom) hide)
    )
    (property "Author" "Antmicro" (at 364.49 102.235 0)
      (effects (font (size 1.27 1.27) (thickness 0.15)) (justify left bottom) hide)
    )
    (property "Tolerance" "1%" (at 364.49 84.455 0)
      (effects (font (size 1.27 1.27)) (justify left bottom) hide)
    )
    (pin "1")
    (pin "2")
    (instances
      (project "data-center-rdimm-ddr4-tester"
        (path ""
          (reference "R152") (unit 1)
        )
      )
    )
  )

  (symbol (lib_id "antmicroResistors0402:R_4k7_0402") (at 203.835 219.71 90) (mirror x) (unit 1)
    (in_bom yes) (on_board yes) (dnp no) (fields_autoplaced)
    (property "Reference" "R160" (at 205.74 220.98 90)
      (effects (font (size 1.524 1.524)) (justify right))
    )
    (property "Value" "R_4k7_0402" (at 216.535 240.03 0)
      (effects (font (size 1.27 1.27) (thickness 0.15)) (justify left bottom) hide)
    )
    (property "Footprint" "antmicro-footprints:R_0402_1005Metric" (at 219.075 240.03 0)
      (effects (font (size 1.27 1.27) (thickness 0.15)) (justify left bottom) hide)
    )
    (property "Datasheet" "https://www.bourns.com/docs/product-datasheets/cr.pdf" (at 221.615 240.03 0)
      (effects (font (size 1.27 1.27) (thickness 0.15)) (justify left bottom) hide)
    )
    (property "Manufacturer" "Bourns" (at 226.695 240.03 0)
      (effects (font (size 1.27 1.27) (thickness 0.15)) (justify left bottom) hide)
    )
    (property "MPN" "CR0402-FX-4701GLF" (at 224.155 240.03 0)
      (effects (font (size 1.27 1.27) (thickness 0.15)) (justify left bottom) hide)
    )
    (property "Val" "4k7" (at 205.74 224.1549 90)
      (effects (font (size 1.27 1.27) (thickness 0.15)) (justify right))
    )
    (property "License" "Apache-2.0" (at 229.235 240.03 0)
      (effects (font (size 1.27 1.27) (thickness 0.15)) (justify left bottom) hide)
    )
    (property "Author" "Antmicro" (at 231.775 240.03 0)
      (effects (font (size 1.27 1.27) (thickness 0.15)) (justify left bottom) hide)
    )
    (property "Tolerance" "1%" (at 213.995 240.03 0)
      (effects (font (size 1.27 1.27)) (justify left bottom) hide)
    )
    (pin "1")
    (pin "2")
    (instances
      (project "data-center-rdimm-ddr4-tester"
        (path ""
          (reference "R160") (unit 1)
        )
      )
    )
  )

  (symbol (lib_id "antmicroCapacitorsmisc:C_47u_16V_1206") (at 238.76 246.38 270) (unit 1)
    (in_bom yes) (on_board yes) (dnp no)
    (property "Reference" "C258" (at 239.395 247.015 90)
      (effects (font (size 1.524 1.524)) (justify left))
    )
    (property "Value" "C_47u_16V_1206" (at 228.6 266.7 0)
      (effects (font (size 1.27 1.27) (thickness 0.15)) (justify left bottom) hide)
    )
    (property "Footprint" "antmicro-footprints:C_1206_3216Metric" (at 226.06 266.7 0)
      (effects (font (size 1.27 1.27) (thickness 0.15)) (justify left bottom) hide)
    )
    (property "Datasheet" " " (at 223.52 266.7 0)
      (effects (font (size 1.27 1.27) (thickness 0.15)) (justify left bottom) hide)
    )
    (property "Manufacturer" "TDK" (at 218.44 266.7 0)
      (effects (font (size 1.27 1.27) (thickness 0.15)) (justify left bottom) hide)
    )
    (property "MPN" "C3216X5R1C476M160AB" (at 220.98 266.7 0)
      (effects (font (size 1.27 1.27) (thickness 0.15)) (justify left bottom) hide)
    )
    (property "Val" "47u/16V" (at 239.395 250.825 90)
      (effects (font (size 1.27 1.27) (thickness 0.15)) (justify left))
    )
    (property "License" "Apache-2.0" (at 215.9 266.7 0)
      (effects (font (size 1.27 1.27) (thickness 0.15)) (justify left bottom) hide)
    )
    (property "Author" "Antmicro" (at 213.36 266.7 0)
      (effects (font (size 1.27 1.27) (thickness 0.15)) (justify left bottom) hide)
    )
    (property "Voltage" "" (at 210.82 266.7 0)
      (effects (font (size 1.27 1.27)) (justify left bottom) hide)
    )
    (property "Dielectric" "" (at 208.28 266.7 0)
      (effects (font (size 1.27 1.27)) (justify left bottom) hide)
    )
    (pin "1")
    (pin "2")
    (instances
      (project "data-center-rdimm-ddr4-tester"
        (path ""
          (reference "C258") (unit 1)
        )
      )
    )
  )

  (symbol (lib_id "antmicroFMCConnectors:ASP-134486-01") (at 156.21 169.545 0) (unit 4)
    (in_bom yes) (on_board yes) (dnp no) (fields_autoplaced)
    (property "Reference" "J5" (at 171.45 161.925 0)
      (effects (font (size 1.27 1.27)))
    )
    (property "Value" "ASP-134486-01" (at 171.45 164.465 0)
      (effects (font (size 1.27 1.27) (thickness 0.15)))
    )
    (property "Footprint" "antmicro-footprints:FMC_SAMTEC_ASP-134486-01" (at 201.93 180.975 0)
      (effects (font (size 1.27 1.27) (thickness 0.15)) (justify left bottom) hide)
    )
    (property "Datasheet" "https://suddendocs.samtec.com/prints/asp-134486-01-mkt.pdf?_gl=1*a2d3qa*_ga*MzYxMTM5My4xNjYzOTI3MDkz*_ga_3KFNZC07WW*MTY2NDIwMTUxMC4zLjAuMTY2NDIwMTUxMC42MC4wLjA." (at 201.93 183.515 0)
      (effects (font (size 1.27 1.27) (thickness 0.15)) (justify left bottom) hide)
    )
    (property "Manufacturer" "Samtec" (at 201.93 186.055 0)
      (effects (font (size 1.27 1.27) (thickness 0.15)) (justify left bottom) hide)
    )
    (property "MPN" "ASP-134486-01" (at 201.93 188.595 0)
      (effects (font (size 1.27 1.27) (thickness 0.15)) (justify left bottom) hide)
    )
    (property "Author" "Antmicro" (at 201.93 191.135 0)
      (effects (font (size 1.27 1.27) (thickness 0.15)) (justify left bottom) hide)
    )
    (property "License" "Apache-2.0" (at 201.93 193.675 0)
      (effects (font (size 1.27 1.27) (thickness 0.15)) (justify left bottom) hide)
    )
    (pin "J1")
    (pin "J10")
    (pin "J11")
    (pin "J12")
    (pin "J13")
    (pin "J14")
    (pin "J15")
    (pin "J16")
    (pin "J17")
    (pin "J18")
    (pin "J19")
    (pin "J2")
    (pin "J20")
    (pin "J21")
    (pin "J22")
    (pin "J23")
    (pin "J24")
    (pin "J25")
    (pin "J26")
    (pin "J27")
    (pin "J28")
    (pin "J29")
    (pin "J3")
    (pin "J30")
    (pin "J31")
    (pin "J32")
    (pin "J33")
    (pin "J34")
    (pin "J35")
    (pin "J36")
    (pin "J37")
    (pin "J38")
    (pin "J39")
    (pin "J4")
    (pin "J40")
    (pin "J5")
    (pin "J6")
    (pin "J7")
    (pin "J8")
    (pin "J9")
    (pin "K1")
    (pin "K10")
    (pin "K11")
    (pin "K12")
    (pin "K13")
    (pin "K14")
    (pin "K15")
    (pin "K16")
    (pin "K17")
    (pin "K18")
    (pin "K19")
    (pin "K2")
    (pin "K20")
    (pin "K21")
    (pin "K22")
    (pin "K23")
    (pin "K24")
    (pin "K25")
    (pin "K26")
    (pin "K27")
    (pin "K28")
    (pin "K29")
    (pin "K3")
    (pin "K30")
    (pin "K31")
    (pin "K32")
    (pin "K33")
    (pin "K34")
    (pin "K35")
    (pin "K36")
    (pin "K37")
    (pin "K38")
    (pin "K39")
    (pin "K4")
    (pin "K40")
    (pin "K5")
    (pin "K6")
    (pin "K7")
    (pin "K8")
    (pin "K9")
    (pin "G1")
    (pin "G10")
    (pin "G11")
    (pin "G12")
    (pin "G13")
    (pin "G14")
    (pin "G15")
    (pin "G16")
    (pin "G17")
    (pin "G18")
    (pin "G19")
    (pin "G2")
    (pin "G20")
    (pin "G21")
    (pin "G22")
    (pin "G23")
    (pin "G24")
    (pin "G25")
    (pin "G26")
    (pin "G27")
    (pin "G28")
    (pin "G29")
    (pin "G3")
    (pin "G30")
    (pin "G31")
    (pin "G32")
    (pin "G33")
    (pin "G34")
    (pin "G35")
    (pin "G36")
    (pin "G37")
    (pin "G38")
    (pin "G39")
    (pin "G4")
    (pin "G40")
    (pin "G5")
    (pin "G6")
    (pin "G7")
    (pin "G8")
    (pin "G9")
    (pin "H1")
    (pin "H10")
    (pin "H11")
    (pin "H12")
    (pin "H13")
    (pin "H14")
    (pin "H15")
    (pin "H16")
    (pin "H17")
    (pin "H18")
    (pin "H19")
    (pin "H2")
    (pin "H20")
    (pin "H21")
    (pin "H22")
    (pin "H23")
    (pin "H24")
    (pin "H25")
    (pin "H26")
    (pin "H27")
    (pin "H28")
    (pin "H29")
    (pin "H3")
    (pin "H30")
    (pin "H31")
    (pin "H32")
    (pin "H33")
    (pin "H34")
    (pin "H35")
    (pin "H36")
    (pin "H37")
    (pin "H38")
    (pin "H39")
    (pin "H4")
    (pin "H40")
    (pin "H5")
    (pin "H6")
    (pin "H7")
    (pin "H8")
    (pin "H9")
    (pin "E1")
    (pin "E10")
    (pin "E11")
    (pin "E12")
    (pin "E13")
    (pin "E14")
    (pin "E15")
    (pin "E16")
    (pin "E17")
    (pin "E18")
    (pin "E19")
    (pin "E2")
    (pin "E20")
    (pin "E21")
    (pin "E22")
    (pin "E23")
    (pin "E24")
    (pin "E25")
    (pin "E26")
    (pin "E27")
    (pin "E28")
    (pin "E29")
    (pin "E3")
    (pin "E30")
    (pin "E31")
    (pin "E32")
    (pin "E33")
    (pin "E34")
    (pin "E35")
    (pin "E36")
    (pin "E37")
    (pin "E38")
    (pin "E39")
    (pin "E4")
    (pin "E40")
    (pin "E5")
    (pin "E6")
    (pin "E7")
    (pin "E8")
    (pin "E9")
    (pin "F1")
    (pin "F10")
    (pin "F11")
    (pin "F12")
    (pin "F13")
    (pin "F14")
    (pin "F15")
    (pin "F16")
    (pin "F17")
    (pin "F18")
    (pin "F19")
    (pin "F2")
    (pin "F20")
    (pin "F21")
    (pin "F22")
    (pin "F23")
    (pin "F24")
    (pin "F25")
    (pin "F26")
    (pin "F27")
    (pin "F28")
    (pin "F29")
    (pin "F3")
    (pin "F30")
    (pin "F31")
    (pin "F32")
    (pin "F33")
    (pin "F34")
    (pin "F35")
    (pin "F36")
    (pin "F37")
    (pin "F38")
    (pin "F39")
    (pin "F4")
    (pin "F40")
    (pin "F5")
    (pin "F6")
    (pin "F7")
    (pin "F8")
    (pin "F9")
    (pin "C1")
    (pin "C10")
    (pin "C11")
    (pin "C12")
    (pin "C13")
    (pin "C14")
    (pin "C15")
    (pin "C16")
    (pin "C17")
    (pin "C18")
    (pin "C19")
    (pin "C2")
    (pin "C20")
    (pin "C21")
    (pin "C22")
    (pin "C23")
    (pin "C24")
    (pin "C25")
    (pin "C26")
    (pin "C27")
    (pin "C28")
    (pin "C29")
    (pin "C3")
    (pin "C30")
    (pin "C31")
    (pin "C32")
    (pin "C33")
    (pin "C34")
    (pin "C35")
    (pin "C36")
    (pin "C37")
    (pin "C38")
    (pin "C39")
    (pin "C4")
    (pin "C40")
    (pin "C5")
    (pin "C6")
    (pin "C7")
    (pin "C8")
    (pin "C9")
    (pin "D1")
    (pin "D10")
    (pin "D11")
    (pin "D12")
    (pin "D13")
    (pin "D14")
    (pin "D15")
    (pin "D16")
    (pin "D17")
    (pin "D18")
    (pin "D19")
    (pin "D2")
    (pin "D20")
    (pin "D21")
    (pin "D22")
    (pin "D23")
    (pin "D24")
    (pin "D25")
    (pin "D26")
    (pin "D27")
    (pin "D28")
    (pin "D29")
    (pin "D3")
    (pin "D30")
    (pin "D31")
    (pin "D32")
    (pin "D33")
    (pin "D34")
    (pin "D35")
    (pin "D36")
    (pin "D37")
    (pin "D38")
    (pin "D39")
    (pin "D4")
    (pin "D40")
    (pin "D5")
    (pin "D6")
    (pin "D7")
    (pin "D8")
    (pin "D9")
    (pin "A1")
    (pin "A10")
    (pin "A11")
    (pin "A12")
    (pin "A13")
    (pin "A14")
    (pin "A15")
    (pin "A16")
    (pin "A17")
    (pin "A18")
    (pin "A19")
    (pin "A2")
    (pin "A20")
    (pin "A21")
    (pin "A22")
    (pin "A23")
    (pin "A24")
    (pin "A25")
    (pin "A26")
    (pin "A27")
    (pin "A28")
    (pin "A29")
    (pin "A3")
    (pin "A30")
    (pin "A31")
    (pin "A32")
    (pin "A33")
    (pin "A34")
    (pin "A35")
    (pin "A36")
    (pin "A37")
    (pin "A38")
    (pin "A39")
    (pin "A4")
    (pin "A40")
    (pin "A5")
    (pin "A6")
    (pin "A7")
    (pin "A8")
    (pin "A9")
    (pin "B1")
    (pin "B10")
    (pin "B11")
    (pin "B12")
    (pin "B13")
    (pin "B14")
    (pin "B15")
    (pin "B16")
    (pin "B17")
    (pin "B18")
    (pin "B19")
    (pin "B2")
    (pin "B20")
    (pin "B21")
    (pin "B22")
    (pin "B23")
    (pin "B24")
    (pin "B25")
    (pin "B26")
    (pin "B27")
    (pin "B28")
    (pin "B29")
    (pin "B3")
    (pin "B30")
    (pin "B31")
    (pin "B32")
    (pin "B33")
    (pin "B34")
    (pin "B35")
    (pin "B36")
    (pin "B37")
    (pin "B38")
    (pin "B39")
    (pin "B4")
    (pin "B40")
    (pin "B5")
    (pin "B6")
    (pin "B7")
    (pin "B8")
    (pin "B9")
    (instances
      (project "data-center-rdimm-ddr4-tester"
        (path ""
          (reference "J5") (unit 4)
        )
      )
    )
  )

  (symbol (lib_id "antmicroCapacitors0402:C_100n_0402") (at 337.82 103.505 0) (unit 1)
    (in_bom yes) (on_board yes) (dnp no)
    (property "Reference" "C261" (at 336.55 102.235 0)
      (effects (font (size 1.524 1.524)))
    )
    (property "Value" "C_100n_0402" (at 358.14 113.665 0)
      (effects (font (size 1.27 1.27) (thickness 0.15)) (justify left bottom) hide)
    )
    (property "Footprint" "antmicro-footprints:C_0402_1005Metric" (at 358.14 116.205 0)
      (effects (font (size 1.27 1.27) (thickness 0.15)) (justify left bottom) hide)
    )
    (property "Datasheet" "https://search.murata.co.jp/Ceramy/image/img/A01X/G101/ENG/GRM155R61H104KE14-01.pdf" (at 358.14 118.745 0)
      (effects (font (size 1.27 1.27) (thickness 0.15)) (justify left bottom) hide)
    )
    (property "Manufacturer" "Murata" (at 358.14 123.825 0)
      (effects (font (size 1.27 1.27) (thickness 0.15)) (justify left bottom) hide)
    )
    (property "MPN" "GRM155R61H104KE14D" (at 358.14 121.285 0)
      (effects (font (size 1.27 1.27) (thickness 0.15)) (justify left bottom) hide)
    )
    (property "Val" "100n" (at 343.535 102.235 0)
      (effects (font (size 1.27 1.27) (thickness 0.15)))
    )
    (property "License" "Apache-2.0" (at 358.14 126.365 0)
      (effects (font (size 1.27 1.27) (thickness 0.15)) (justify left bottom) hide)
    )
    (property "Author" "Antmicro" (at 358.14 128.905 0)
      (effects (font (size 1.27 1.27) (thickness 0.15)) (justify left bottom) hide)
    )
    (property "Voltage" "50V" (at 358.14 131.445 0)
      (effects (font (size 1.27 1.27)) (justify left bottom) hide)
    )
    (property "Dielectric" "X5R" (at 358.14 133.985 0)
      (effects (font (size 1.27 1.27)) (justify left bottom) hide)
    )
    (pin "1")
    (pin "2")
    (instances
      (project "data-center-rdimm-ddr4-tester"
        (path ""
          (reference "C261") (unit 1)
        )
      )
    )
  )

  (symbol (lib_id "antmicroCapacitors0402:C_100n_0402") (at 337.82 113.665 0) (unit 1)
    (in_bom yes) (on_board yes) (dnp no)
    (property "Reference" "C263" (at 336.55 112.395 0)
      (effects (font (size 1.524 1.524)))
    )
    (property "Value" "C_100n_0402" (at 358.14 123.825 0)
      (effects (font (size 1.27 1.27) (thickness 0.15)) (justify left bottom) hide)
    )
    (property "Footprint" "antmicro-footprints:C_0402_1005Metric" (at 358.14 126.365 0)
      (effects (font (size 1.27 1.27) (thickness 0.15)) (justify left bottom) hide)
    )
    (property "Datasheet" "https://search.murata.co.jp/Ceramy/image/img/A01X/G101/ENG/GRM155R61H104KE14-01.pdf" (at 358.14 128.905 0)
      (effects (font (size 1.27 1.27) (thickness 0.15)) (justify left bottom) hide)
    )
    (property "Manufacturer" "Murata" (at 358.14 133.985 0)
      (effects (font (size 1.27 1.27) (thickness 0.15)) (justify left bottom) hide)
    )
    (property "MPN" "GRM155R61H104KE14D" (at 358.14 131.445 0)
      (effects (font (size 1.27 1.27) (thickness 0.15)) (justify left bottom) hide)
    )
    (property "Val" "100n" (at 343.535 112.395 0)
      (effects (font (size 1.27 1.27) (thickness 0.15)))
    )
    (property "License" "Apache-2.0" (at 358.14 136.525 0)
      (effects (font (size 1.27 1.27) (thickness 0.15)) (justify left bottom) hide)
    )
    (property "Author" "Antmicro" (at 358.14 139.065 0)
      (effects (font (size 1.27 1.27) (thickness 0.15)) (justify left bottom) hide)
    )
    (property "Voltage" "50V" (at 358.14 141.605 0)
      (effects (font (size 1.27 1.27)) (justify left bottom) hide)
    )
    (property "Dielectric" "X5R" (at 358.14 144.145 0)
      (effects (font (size 1.27 1.27)) (justify left bottom) hide)
    )
    (pin "1")
    (pin "2")
    (instances
      (project "data-center-rdimm-ddr4-tester"
        (path ""
          (reference "C263") (unit 1)
        )
      )
    )
  )

  (symbol (lib_id "antmicroCapacitors0402:C_100n_0402") (at 337.82 154.305 0) (unit 1)
    (in_bom yes) (on_board yes) (dnp no)
    (property "Reference" "C271" (at 336.55 153.035 0)
      (effects (font (size 1.524 1.524)))
    )
    (property "Value" "C_100n_0402" (at 358.14 164.465 0)
      (effects (font (size 1.27 1.27) (thickness 0.15)) (justify left bottom) hide)
    )
    (property "Footprint" "antmicro-footprints:C_0402_1005Metric" (at 358.14 167.005 0)
      (effects (font (size 1.27 1.27) (thickness 0.15)) (justify left bottom) hide)
    )
    (property "Datasheet" "https://search.murata.co.jp/Ceramy/image/img/A01X/G101/ENG/GRM155R61H104KE14-01.pdf" (at 358.14 169.545 0)
      (effects (font (size 1.27 1.27) (thickness 0.15)) (justify left bottom) hide)
    )
    (property "Manufacturer" "Murata" (at 358.14 174.625 0)
      (effects (font (size 1.27 1.27) (thickness 0.15)) (justify left bottom) hide)
    )
    (property "MPN" "GRM155R61H104KE14D" (at 358.14 172.085 0)
      (effects (font (size 1.27 1.27) (thickness 0.15)) (justify left bottom) hide)
    )
    (property "Val" "100n" (at 343.535 153.035 0)
      (effects (font (size 1.27 1.27) (thickness 0.15)))
    )
    (property "License" "Apache-2.0" (at 358.14 177.165 0)
      (effects (font (size 1.27 1.27) (thickness 0.15)) (justify left bottom) hide)
    )
    (property "Author" "Antmicro" (at 358.14 179.705 0)
      (effects (font (size 1.27 1.27) (thickness 0.15)) (justify left bottom) hide)
    )
    (property "Voltage" "50V" (at 358.14 182.245 0)
      (effects (font (size 1.27 1.27)) (justify left bottom) hide)
    )
    (property "Dielectric" "X5R" (at 358.14 184.785 0)
      (effects (font (size 1.27 1.27)) (justify left bottom) hide)
    )
    (pin "1")
    (pin "2")
    (instances
      (project "data-center-rdimm-ddr4-tester"
        (path ""
          (reference "C271") (unit 1)
        )
      )
    )
  )

  (symbol (lib_id "antmicroCapacitors0402:C_100n_0402") (at 337.82 164.465 0) (unit 1)
    (in_bom yes) (on_board yes) (dnp no)
    (property "Reference" "C273" (at 336.55 163.195 0)
      (effects (font (size 1.524 1.524)))
    )
    (property "Value" "C_100n_0402" (at 358.14 174.625 0)
      (effects (font (size 1.27 1.27) (thickness 0.15)) (justify left bottom) hide)
    )
    (property "Footprint" "antmicro-footprints:C_0402_1005Metric" (at 358.14 177.165 0)
      (effects (font (size 1.27 1.27) (thickness 0.15)) (justify left bottom) hide)
    )
    (property "Datasheet" "https://search.murata.co.jp/Ceramy/image/img/A01X/G101/ENG/GRM155R61H104KE14-01.pdf" (at 358.14 179.705 0)
      (effects (font (size 1.27 1.27) (thickness 0.15)) (justify left bottom) hide)
    )
    (property "Manufacturer" "Murata" (at 358.14 184.785 0)
      (effects (font (size 1.27 1.27) (thickness 0.15)) (justify left bottom) hide)
    )
    (property "MPN" "GRM155R61H104KE14D" (at 358.14 182.245 0)
      (effects (font (size 1.27 1.27) (thickness 0.15)) (justify left bottom) hide)
    )
    (property "Val" "100n" (at 343.535 163.195 0)
      (effects (font (size 1.27 1.27) (thickness 0.15)))
    )
    (property "License" "Apache-2.0" (at 358.14 187.325 0)
      (effects (font (size 1.27 1.27) (thickness 0.15)) (justify left bottom) hide)
    )
    (property "Author" "Antmicro" (at 358.14 189.865 0)
      (effects (font (size 1.27 1.27) (thickness 0.15)) (justify left bottom) hide)
    )
    (property "Voltage" "50V" (at 358.14 192.405 0)
      (effects (font (size 1.27 1.27)) (justify left bottom) hide)
    )
    (property "Dielectric" "X5R" (at 358.14 194.945 0)
      (effects (font (size 1.27 1.27)) (justify left bottom) hide)
    )
    (pin "1")
    (pin "2")
    (instances
      (project "data-center-rdimm-ddr4-tester"
        (path ""
          (reference "C273") (unit 1)
        )
      )
    )
  )

  (symbol (lib_id "antmicroCapacitors0402:C_100n_0402") (at 349.25 126.365 0) (unit 1)
    (in_bom yes) (on_board yes) (dnp no)
    (property "Reference" "C266" (at 347.98 125.095 0)
      (effects (font (size 1.524 1.524)))
    )
    (property "Value" "C_100n_0402" (at 369.57 136.525 0)
      (effects (font (size 1.27 1.27) (thickness 0.15)) (justify left bottom) hide)
    )
    (property "Footprint" "antmicro-footprints:C_0402_1005Metric" (at 369.57 139.065 0)
      (effects (font (size 1.27 1.27) (thickness 0.15)) (justify left bottom) hide)
    )
    (property "Datasheet" "https://search.murata.co.jp/Ceramy/image/img/A01X/G101/ENG/GRM155R61H104KE14-01.pdf" (at 369.57 141.605 0)
      (effects (font (size 1.27 1.27) (thickness 0.15)) (justify left bottom) hide)
    )
    (property "Manufacturer" "Murata" (at 369.57 146.685 0)
      (effects (font (size 1.27 1.27) (thickness 0.15)) (justify left bottom) hide)
    )
    (property "MPN" "GRM155R61H104KE14D" (at 369.57 144.145 0)
      (effects (font (size 1.27 1.27) (thickness 0.15)) (justify left bottom) hide)
    )
    (property "Val" "100n" (at 354.965 125.095 0)
      (effects (font (size 1.27 1.27) (thickness 0.15)))
    )
    (property "License" "Apache-2.0" (at 369.57 149.225 0)
      (effects (font (size 1.27 1.27) (thickness 0.15)) (justify left bottom) hide)
    )
    (property "Author" "Antmicro" (at 369.57 151.765 0)
      (effects (font (size 1.27 1.27) (thickness 0.15)) (justify left bottom) hide)
    )
    (property "Voltage" "50V" (at 369.57 154.305 0)
      (effects (font (size 1.27 1.27)) (justify left bottom) hide)
    )
    (property "Dielectric" "X5R" (at 369.57 156.845 0)
      (effects (font (size 1.27 1.27)) (justify left bottom) hide)
    )
    (pin "1")
    (pin "2")
    (instances
      (project "data-center-rdimm-ddr4-tester"
        (path ""
          (reference "C266") (unit 1)
        )
      )
    )
  )

  (symbol (lib_id "antmicroCapacitors0402:C_100n_0402") (at 349.25 95.885 0) (unit 1)
    (in_bom yes) (on_board yes) (dnp no)
    (property "Reference" "C260" (at 347.98 94.615 0)
      (effects (font (size 1.524 1.524)))
    )
    (property "Value" "C_100n_0402" (at 369.57 106.045 0)
      (effects (font (size 1.27 1.27) (thickness 0.15)) (justify left bottom) hide)
    )
    (property "Footprint" "antmicro-footprints:C_0402_1005Metric" (at 369.57 108.585 0)
      (effects (font (size 1.27 1.27) (thickness 0.15)) (justify left bottom) hide)
    )
    (property "Datasheet" "https://search.murata.co.jp/Ceramy/image/img/A01X/G101/ENG/GRM155R61H104KE14-01.pdf" (at 369.57 111.125 0)
      (effects (font (size 1.27 1.27) (thickness 0.15)) (justify left bottom) hide)
    )
    (property "Manufacturer" "Murata" (at 369.57 116.205 0)
      (effects (font (size 1.27 1.27) (thickness 0.15)) (justify left bottom) hide)
    )
    (property "MPN" "GRM155R61H104KE14D" (at 369.57 113.665 0)
      (effects (font (size 1.27 1.27) (thickness 0.15)) (justify left bottom) hide)
    )
    (property "Val" "100n" (at 354.965 94.615 0)
      (effects (font (size 1.27 1.27) (thickness 0.15)))
    )
    (property "License" "Apache-2.0" (at 369.57 118.745 0)
      (effects (font (size 1.27 1.27) (thickness 0.15)) (justify left bottom) hide)
    )
    (property "Author" "Antmicro" (at 369.57 121.285 0)
      (effects (font (size 1.27 1.27) (thickness 0.15)) (justify left bottom) hide)
    )
    (property "Voltage" "50V" (at 369.57 123.825 0)
      (effects (font (size 1.27 1.27)) (justify left bottom) hide)
    )
    (property "Dielectric" "X5R" (at 369.57 126.365 0)
      (effects (font (size 1.27 1.27)) (justify left bottom) hide)
    )
    (pin "1")
    (pin "2")
    (instances
      (project "data-center-rdimm-ddr4-tester"
        (path ""
          (reference "C260") (unit 1)
        )
      )
    )
  )

  (symbol (lib_id "antmicroCapacitors0402:C_100n_0402") (at 337.82 93.345 0) (unit 1)
    (in_bom yes) (on_board yes) (dnp no)
    (property "Reference" "C259" (at 336.55 92.075 0)
      (effects (font (size 1.524 1.524)))
    )
    (property "Value" "C_100n_0402" (at 358.14 103.505 0)
      (effects (font (size 1.27 1.27) (thickness 0.15)) (justify left bottom) hide)
    )
    (property "Footprint" "antmicro-footprints:C_0402_1005Metric" (at 358.14 106.045 0)
      (effects (font (size 1.27 1.27) (thickness 0.15)) (justify left bottom) hide)
    )
    (property "Datasheet" "https://search.murata.co.jp/Ceramy/image/img/A01X/G101/ENG/GRM155R61H104KE14-01.pdf" (at 358.14 108.585 0)
      (effects (font (size 1.27 1.27) (thickness 0.15)) (justify left bottom) hide)
    )
    (property "Manufacturer" "Murata" (at 358.14 113.665 0)
      (effects (font (size 1.27 1.27) (thickness 0.15)) (justify left bottom) hide)
    )
    (property "MPN" "GRM155R61H104KE14D" (at 358.14 111.125 0)
      (effects (font (size 1.27 1.27) (thickness 0.15)) (justify left bottom) hide)
    )
    (property "Val" "100n" (at 343.535 92.075 0)
      (effects (font (size 1.27 1.27) (thickness 0.15)))
    )
    (property "License" "Apache-2.0" (at 358.14 116.205 0)
      (effects (font (size 1.27 1.27) (thickness 0.15)) (justify left bottom) hide)
    )
    (property "Author" "Antmicro" (at 358.14 118.745 0)
      (effects (font (size 1.27 1.27) (thickness 0.15)) (justify left bottom) hide)
    )
    (property "Voltage" "50V" (at 358.14 121.285 0)
      (effects (font (size 1.27 1.27)) (justify left bottom) hide)
    )
    (property "Dielectric" "X5R" (at 358.14 123.825 0)
      (effects (font (size 1.27 1.27)) (justify left bottom) hide)
    )
    (pin "1")
    (pin "2")
    (instances
      (project "data-center-rdimm-ddr4-tester"
        (path ""
          (reference "C259") (unit 1)
        )
      )
    )
  )
)
